(kicad_sch
	(version 20250114)
	(generator "eeschema")
	(generator_version "9.0")
	(paper "A3")
	(title_block
		(title "OCuLink to 10GbE adapter")
		(date "2026-02-23")
		(rev "1.1.0")
		(company "Antmicro Ltd")
		(comment 1 "www.antmicro.com")
	)
	(bus_alias "I2C"
		(members "SDA" "SCL")
	)
	(bus_alias "MDIO"
		(members "MDIO" "MDC")
	)
	(bus_alias "NCSI"
		(members "ARB_IN" "ARB_OUT" "REF_CLK" "CRS_DV" "TX_EN" "TXD_0" "RXD_0"
			"TXD_1" "RXD_1"
		)
	)
	(bus_alias "SPI"
		(members "~{CE}" "CLK" "MISO" "MOSI")
	)
	(text "X710-AT2 Miscellaneous"
		(exclude_from_sim no)
		(at 215.9 25.4 0)
		(effects
			(font
				(size 2.54 2.54)
				(thickness 0.508)
				(bold yes)
			)
		)
	)
	(junction
		(at 265.43 104.14)
		(diameter 0)
		(color 0 0 0 0)
	)
	(junction
		(at 128.27 66.04)
		(diameter 0)
		(color 0 0 0 0)
	)
	(junction
		(at 135.89 116.84)
		(diameter 0)
		(color 0 0 0 0)
	)
	(junction
		(at 245.11 149.86)
		(diameter 0)
		(color 0 0 0 0)
	)
	(junction
		(at 274.32 116.84)
		(diameter 0)
		(color 0 0 0 0)
	)
	(junction
		(at 135.89 96.52)
		(diameter 0)
		(color 0 0 0 0)
	)
	(junction
		(at 160.02 190.5)
		(diameter 0)
		(color 0 0 0 0)
	)
	(junction
		(at 118.11 121.92)
		(diameter 0)
		(color 0 0 0 0)
	)
	(junction
		(at 242.57 215.9)
		(diameter 0)
		(color 0 0 0 0)
	)
	(junction
		(at 274.32 114.3)
		(diameter 0)
		(color 0 0 0 0)
	)
	(junction
		(at 92.71 227.33)
		(diameter 0)
		(color 0 0 0 0)
	)
	(junction
		(at 44.45 104.14)
		(diameter 0)
		(color 0 0 0 0)
	)
	(junction
		(at 256.54 88.9)
		(diameter 0)
		(color 0 0 0 0)
	)
	(junction
		(at 67.31 171.45)
		(diameter 0)
		(color 0 0 0 0)
	)
	(junction
		(at 154.94 106.68)
		(diameter 0)
		(color 0 0 0 0)
	)
	(junction
		(at 106.68 213.36)
		(diameter 0)
		(color 0 0 0 0)
	)
	(junction
		(at 146.05 53.34)
		(diameter 0)
		(color 0 0 0 0)
	)
	(junction
		(at 242.57 218.44)
		(diameter 0)
		(color 0 0 0 0)
	)
	(junction
		(at 53.34 229.87)
		(diameter 0)
		(color 0 0 0 0)
	)
	(junction
		(at 242.57 210.82)
		(diameter 0)
		(color 0 0 0 0)
	)
	(junction
		(at 128.27 160.02)
		(diameter 0)
		(color 0 0 0 0)
	)
	(junction
		(at 242.57 213.36)
		(diameter 0)
		(color 0 0 0 0)
	)
	(junction
		(at 146.05 96.52)
		(diameter 0)
		(color 0 0 0 0)
	)
	(junction
		(at 41.91 104.14)
		(diameter 0)
		(color 0 0 0 0)
	)
	(junction
		(at 121.92 60.96)
		(diameter 0)
		(color 0 0 0 0)
	)
	(junction
		(at 67.31 213.36)
		(diameter 0)
		(color 0 0 0 0)
	)
	(junction
		(at 110.49 96.52)
		(diameter 0)
		(color 0 0 0 0)
	)
	(junction
		(at 127 119.38)
		(diameter 0)
		(color 0 0 0 0)
	)
	(junction
		(at 241.3 160.02)
		(diameter 0)
		(color 0 0 0 0)
	)
	(junction
		(at 139.7 55.88)
		(diameter 0)
		(color 0 0 0 0)
	)
	(junction
		(at 92.71 185.42)
		(diameter 0)
		(color 0 0 0 0)
	)
	(junction
		(at 137.16 63.5)
		(diameter 0)
		(color 0 0 0 0)
	)
	(junction
		(at 97.79 171.45)
		(diameter 0)
		(color 0 0 0 0)
	)
	(junction
		(at 163.83 187.96)
		(diameter 0)
		(color 0 0 0 0)
	)
	(junction
		(at 119.38 68.58)
		(diameter 0)
		(color 0 0 0 0)
	)
	(junction
		(at 106.68 229.87)
		(diameter 0)
		(color 0 0 0 0)
	)
	(junction
		(at 33.02 104.14)
		(diameter 0)
		(color 0 0 0 0)
	)
	(junction
		(at 256.54 101.6)
		(diameter 0)
		(color 0 0 0 0)
	)
	(junction
		(at 110.49 40.64)
		(diameter 0)
		(color 0 0 0 0)
	)
	(junction
		(at 163.83 177.8)
		(diameter 0)
		(color 0 0 0 0)
	)
	(junction
		(at 110.49 71.12)
		(diameter 0)
		(color 0 0 0 0)
	)
	(junction
		(at 245.11 162.56)
		(diameter 0)
		(color 0 0 0 0)
	)
	(junction
		(at 96.52 213.36)
		(diameter 0)
		(color 0 0 0 0)
	)
	(junction
		(at 62.23 213.36)
		(diameter 0)
		(color 0 0 0 0)
	)
	(junction
		(at 148.59 50.8)
		(diameter 0)
		(color 0 0 0 0)
	)
	(junction
		(at 118.11 96.52)
		(diameter 0)
		(color 0 0 0 0)
	)
	(junction
		(at 265.43 88.9)
		(diameter 0)
		(color 0 0 0 0)
	)
	(junction
		(at 146.05 109.22)
		(diameter 0)
		(color 0 0 0 0)
	)
	(junction
		(at 114.3 119.38)
		(diameter 0)
		(color 0 0 0 0)
	)
	(junction
		(at 64.77 121.92)
		(diameter 0)
		(color 0 0 0 0)
	)
	(junction
		(at 130.81 58.42)
		(diameter 0)
		(color 0 0 0 0)
	)
	(junction
		(at 172.72 177.8)
		(diameter 0)
		(color 0 0 0 0)
	)
	(junction
		(at 57.15 104.14)
		(diameter 0)
		(color 0 0 0 0)
	)
	(junction
		(at 127 96.52)
		(diameter 0)
		(color 0 0 0 0)
	)
	(junction
		(at 137.16 162.56)
		(diameter 0)
		(color 0 0 0 0)
	)
	(junction
		(at 124.46 119.38)
		(diameter 0)
		(color 0 0 0 0)
	)
	(junction
		(at 274.32 88.9)
		(diameter 0)
		(color 0 0 0 0)
	)
	(junction
		(at 128.27 40.64)
		(diameter 0)
		(color 0 0 0 0)
	)
	(junction
		(at 137.16 40.64)
		(diameter 0)
		(color 0 0 0 0)
	)
	(junction
		(at 119.38 40.64)
		(diameter 0)
		(color 0 0 0 0)
	)
	(no_connect
		(at 238.76 238.76)
	)
	(no_connect
		(at 238.76 185.42)
	)
	(no_connect
		(at 238.76 172.72)
	)
	(no_connect
		(at 238.76 233.68)
	)
	(no_connect
		(at 182.88 175.26)
	)
	(no_connect
		(at 238.76 198.12)
	)
	(no_connect
		(at 233.68 83.82)
	)
	(no_connect
		(at 238.76 175.26)
	)
	(no_connect
		(at 182.88 182.88)
	)
	(no_connect
		(at 238.76 195.58)
	)
	(no_connect
		(at 238.76 167.64)
	)
	(no_connect
		(at 238.76 182.88)
	)
	(no_connect
		(at 238.76 236.22)
	)
	(no_connect
		(at 182.88 180.34)
	)
	(no_connect
		(at 182.88 172.72)
	)
	(no_connect
		(at 182.88 200.66)
	)
	(no_connect
		(at 238.76 200.66)
	)
	(no_connect
		(at 182.88 205.74)
	)
	(no_connect
		(at 238.76 231.14)
	)
	(no_connect
		(at 238.76 170.18)
	)
	(no_connect
		(at 238.76 246.38)
	)
	(no_connect
		(at 182.88 198.12)
	)
	(no_connect
		(at 233.68 76.2)
	)
	(no_connect
		(at 238.76 187.96)
	)
	(no_connect
		(at 238.76 226.06)
	)
	(no_connect
		(at 238.76 243.84)
	)
	(no_connect
		(at 238.76 228.6)
	)
	(no_connect
		(at 238.76 193.04)
	)
	(no_connect
		(at 182.88 203.2)
	)
	(no_connect
		(at 238.76 180.34)
	)
	(no_connect
		(at 233.68 81.28)
	)
	(no_connect
		(at 238.76 223.52)
	)
	(no_connect
		(at 238.76 241.3)
	)
	(bus_entry
		(at 304.8 121.92)
		(size -2.54 -2.54)
		(stroke
			(width 0)
			(type default)
		)
	)
	(bus_entry
		(at 304.8 104.14)
		(size -2.54 -2.54)
		(stroke
			(width 0)
			(type default)
		)
	)
	(bus_entry
		(at 304.8 106.68)
		(size -2.54 -2.54)
		(stroke
			(width 0)
			(type default)
		)
	)
	(bus_entry
		(at 41.91 190.5)
		(size 2.54 -2.54)
		(stroke
			(width 0)
			(type default)
		)
	)
	(bus_entry
		(at 304.8 124.46)
		(size -2.54 -2.54)
		(stroke
			(width 0)
			(type default)
		)
	)
	(bus_entry
		(at 304.8 119.38)
		(size -2.54 -2.54)
		(stroke
			(width 0)
			(type default)
		)
	)
	(bus_entry
		(at 41.91 193.04)
		(size 2.54 -2.54)
		(stroke
			(width 0)
			(type default)
		)
	)
	(bus_entry
		(at 304.8 116.84)
		(size -2.54 -2.54)
		(stroke
			(width 0)
			(type default)
		)
	)
	(wire
		(pts
			(xy 172.72 63.5) (xy 172.72 88.9)
		)
		(stroke
			(width 0)
			(type default)
		)
	)
	(wire
		(pts
			(xy 124.46 119.38) (xy 124.46 124.46)
		)
		(stroke
			(width 0)
			(type default)
		)
	)
	(wire
		(pts
			(xy 64.77 114.3) (xy 64.77 121.92)
		)
		(stroke
			(width 0)
			(type default)
		)
	)
	(wire
		(pts
			(xy 53.34 229.87) (xy 69.85 229.87)
		)
		(stroke
			(width 0)
			(type default)
		)
	)
	(wire
		(pts
			(xy 96.52 213.36) (xy 106.68 213.36)
		)
		(stroke
			(width 0)
			(type default)
		)
	)
	(wire
		(pts
			(xy 267.97 196.85) (xy 267.97 199.39)
		)
		(stroke
			(width 0)
			(type default)
		)
	)
	(wire
		(pts
			(xy 265.43 104.14) (xy 302.26 104.14)
		)
		(stroke
			(width 0)
			(type default)
		)
	)
	(wire
		(pts
			(xy 274.32 129.54) (xy 274.32 132.08)
		)
		(stroke
			(width 0)
			(type default)
		)
	)
	(wire
		(pts
			(xy 53.34 220.98) (xy 53.34 229.87)
		)
		(stroke
			(width 0)
			(type default)
		)
	)
	(bus
		(pts
			(xy 41.91 193.04) (xy 41.91 195.58)
		)
		(stroke
			(width 0)
			(type default)
		)
	)
	(wire
		(pts
			(xy 128.27 43.18) (xy 128.27 40.64)
		)
		(stroke
			(width 0)
			(type default)
		)
	)
	(wire
		(pts
			(xy 233.68 86.36) (xy 262.89 86.36)
		)
		(stroke
			(width 0)
			(type default)
		)
	)
	(wire
		(pts
			(xy 140.97 218.44) (xy 182.88 218.44)
		)
		(stroke
			(width 0)
			(type default)
		)
	)
	(wire
		(pts
			(xy 274.32 91.44) (xy 274.32 88.9)
		)
		(stroke
			(width 0)
			(type default)
		)
	)
	(bus
		(pts
			(xy 307.34 111.76) (xy 304.8 109.22)
		)
		(stroke
			(width 0)
			(type default)
		)
	)
	(wire
		(pts
			(xy 247.65 99.06) (xy 247.65 96.52)
		)
		(stroke
			(width 0)
			(type default)
		)
	)
	(wire
		(pts
			(xy 92.71 171.45) (xy 92.71 185.42)
		)
		(stroke
			(width 0)
			(type default)
		)
	)
	(wire
		(pts
			(xy 135.89 96.52) (xy 127 96.52)
		)
		(stroke
			(width 0)
			(type default)
		)
	)
	(wire
		(pts
			(xy 238.76 205.74) (xy 242.57 205.74)
		)
		(stroke
			(width 0)
			(type default)
		)
	)
	(wire
		(pts
			(xy 170.18 233.68) (xy 182.88 233.68)
		)
		(stroke
			(width 0)
			(type default)
		)
	)
	(wire
		(pts
			(xy 64.77 104.14) (xy 57.15 104.14)
		)
		(stroke
			(width 0)
			(type default)
		)
	)
	(wire
		(pts
			(xy 67.31 193.04) (xy 67.31 195.58)
		)
		(stroke
			(width 0)
			(type default)
		)
	)
	(wire
		(pts
			(xy 256.54 88.9) (xy 265.43 88.9)
		)
		(stroke
			(width 0)
			(type default)
		)
	)
	(wire
		(pts
			(xy 90.17 234.95) (xy 92.71 234.95)
		)
		(stroke
			(width 0)
			(type default)
		)
	)
	(wire
		(pts
			(xy 106.68 232.41) (xy 106.68 237.49)
		)
		(stroke
			(width 0)
			(type default)
		)
	)
	(wire
		(pts
			(xy 163.83 180.34) (xy 163.83 177.8)
		)
		(stroke
			(width 0)
			(type default)
		)
	)
	(wire
		(pts
			(xy 242.57 213.36) (xy 242.57 215.9)
		)
		(stroke
			(width 0)
			(type default)
		)
	)
	(wire
		(pts
			(xy 245.11 157.48) (xy 245.11 162.56)
		)
		(stroke
			(width 0)
			(type default)
		)
	)
	(wire
		(pts
			(xy 127 119.38) (xy 187.96 119.38)
		)
		(stroke
			(width 0)
			(type default)
		)
	)
	(wire
		(pts
			(xy 165.1 71.12) (xy 165.1 99.06)
		)
		(stroke
			(width 0)
			(type default)
		)
	)
	(wire
		(pts
			(xy 99.06 232.41) (xy 90.17 232.41)
		)
		(stroke
			(width 0)
			(type default)
		)
	)
	(wire
		(pts
			(xy 90.17 190.5) (xy 160.02 190.5)
		)
		(stroke
			(width 0)
			(type default)
		)
	)
	(wire
		(pts
			(xy 114.3 215.9) (xy 182.88 215.9)
		)
		(stroke
			(width 0)
			(type default)
		)
	)
	(bus
		(pts
			(xy 41.91 190.5) (xy 41.91 193.04)
		)
		(stroke
			(width 0)
			(type default)
		)
	)
	(wire
		(pts
			(xy 137.16 48.26) (xy 137.16 63.5)
		)
		(stroke
			(width 0)
			(type default)
		)
	)
	(wire
		(pts
			(xy 140.97 218.44) (xy 140.97 246.38)
		)
		(stroke
			(width 0)
			(type default)
		)
	)
	(wire
		(pts
			(xy 92.71 66.04) (xy 128.27 66.04)
		)
		(stroke
			(width 0)
			(type default)
		)
	)
	(wire
		(pts
			(xy 242.57 215.9) (xy 242.57 218.44)
		)
		(stroke
			(width 0)
			(type default)
		)
	)
	(wire
		(pts
			(xy 92.71 53.34) (xy 146.05 53.34)
		)
		(stroke
			(width 0)
			(type default)
		)
	)
	(wire
		(pts
			(xy 233.68 121.92) (xy 302.26 121.92)
		)
		(stroke
			(width 0)
			(type default)
		)
	)
	(wire
		(pts
			(xy 128.27 48.26) (xy 128.27 66.04)
		)
		(stroke
			(width 0)
			(type default)
		)
	)
	(wire
		(pts
			(xy 33.02 93.98) (xy 33.02 96.52)
		)
		(stroke
			(width 0)
			(type default)
		)
	)
	(wire
		(pts
			(xy 137.16 43.18) (xy 137.16 40.64)
		)
		(stroke
			(width 0)
			(type default)
		)
	)
	(wire
		(pts
			(xy 172.72 185.42) (xy 172.72 193.04)
		)
		(stroke
			(width 0)
			(type default)
		)
	)
	(wire
		(pts
			(xy 97.79 171.45) (xy 92.71 171.45)
		)
		(stroke
			(width 0)
			(type default)
		)
	)
	(wire
		(pts
			(xy 92.71 63.5) (xy 137.16 63.5)
		)
		(stroke
			(width 0)
			(type default)
		)
	)
	(wire
		(pts
			(xy 241.3 149.86) (xy 241.3 152.4)
		)
		(stroke
			(width 0)
			(type default)
		)
	)
	(wire
		(pts
			(xy 233.68 101.6) (xy 256.54 101.6)
		)
		(stroke
			(width 0)
			(type default)
		)
	)
	(wire
		(pts
			(xy 146.05 43.18) (xy 146.05 40.64)
		)
		(stroke
			(width 0)
			(type default)
		)
	)
	(wire
		(pts
			(xy 44.45 101.6) (xy 44.45 104.14)
		)
		(stroke
			(width 0)
			(type default)
		)
	)
	(wire
		(pts
			(xy 33.02 114.3) (xy 33.02 111.76)
		)
		(stroke
			(width 0)
			(type default)
		)
	)
	(wire
		(pts
			(xy 135.89 116.84) (xy 187.96 116.84)
		)
		(stroke
			(width 0)
			(type default)
		)
	)
	(wire
		(pts
			(xy 110.49 71.12) (xy 153.67 71.12)
		)
		(stroke
			(width 0)
			(type default)
		)
	)
	(wire
		(pts
			(xy 104.14 232.41) (xy 106.68 232.41)
		)
		(stroke
			(width 0)
			(type default)
		)
	)
	(bus
		(pts
			(xy 39.37 198.12) (xy 41.91 195.58)
		)
		(stroke
			(width 0)
			(type default)
		)
	)
	(wire
		(pts
			(xy 274.32 116.84) (xy 302.26 116.84)
		)
		(stroke
			(width 0)
			(type default)
		)
	)
	(bus
		(pts
			(xy 307.34 129.54) (xy 304.8 127)
		)
		(stroke
			(width 0)
			(type default)
		)
	)
	(wire
		(pts
			(xy 44.45 190.5) (xy 69.85 190.5)
		)
		(stroke
			(width 0)
			(type default)
		)
	)
	(wire
		(pts
			(xy 130.81 78.74) (xy 130.81 81.28)
		)
		(stroke
			(width 0)
			(type default)
		)
	)
	(wire
		(pts
			(xy 185.42 50.8) (xy 148.59 50.8)
		)
		(stroke
			(width 0)
			(type default)
		)
	)
	(wire
		(pts
			(xy 44.45 187.96) (xy 69.85 187.96)
		)
		(stroke
			(width 0)
			(type default)
		)
	)
	(wire
		(pts
			(xy 25.4 121.92) (xy 30.48 121.92)
		)
		(stroke
			(width 0)
			(type default)
		)
	)
	(wire
		(pts
			(xy 137.16 40.64) (xy 146.05 40.64)
		)
		(stroke
			(width 0)
			(type default)
		)
	)
	(bus
		(pts
			(xy 304.8 116.84) (xy 304.8 119.38)
		)
		(stroke
			(width 0)
			(type default)
		)
	)
	(bus
		(pts
			(xy 307.34 111.76) (xy 309.88 111.76)
		)
		(stroke
			(width 0)
			(type default)
		)
	)
	(wire
		(pts
			(xy 123.19 208.28) (xy 182.88 208.28)
		)
		(stroke
			(width 0)
			(type default)
		)
	)
	(wire
		(pts
			(xy 92.71 68.58) (xy 119.38 68.58)
		)
		(stroke
			(width 0)
			(type default)
		)
	)
	(wire
		(pts
			(xy 256.54 88.9) (xy 256.54 91.44)
		)
		(stroke
			(width 0)
			(type default)
		)
	)
	(wire
		(pts
			(xy 67.31 168.91) (xy 67.31 171.45)
		)
		(stroke
			(width 0)
			(type default)
		)
	)
	(wire
		(pts
			(xy 172.72 88.9) (xy 187.96 88.9)
		)
		(stroke
			(width 0)
			(type default)
		)
	)
	(wire
		(pts
			(xy 118.11 121.92) (xy 187.96 121.92)
		)
		(stroke
			(width 0)
			(type default)
		)
	)
	(wire
		(pts
			(xy 146.05 99.06) (xy 146.05 96.52)
		)
		(stroke
			(width 0)
			(type default)
		)
	)
	(wire
		(pts
			(xy 132.08 210.82) (xy 182.88 210.82)
		)
		(stroke
			(width 0)
			(type default)
		)
	)
	(bus
		(pts
			(xy 36.83 198.12) (xy 39.37 198.12)
		)
		(stroke
			(width 0)
			(type default)
		)
	)
	(wire
		(pts
			(xy 114.3 129.54) (xy 114.3 132.08)
		)
		(stroke
			(width 0)
			(type default)
		)
	)
	(wire
		(pts
			(xy 238.76 210.82) (xy 242.57 210.82)
		)
		(stroke
			(width 0)
			(type default)
		)
	)
	(wire
		(pts
			(xy 124.46 119.38) (xy 127 119.38)
		)
		(stroke
			(width 0)
			(type default)
		)
	)
	(wire
		(pts
			(xy 177.8 81.28) (xy 187.96 81.28)
		)
		(stroke
			(width 0)
			(type default)
		)
	)
	(wire
		(pts
			(xy 160.02 177.8) (xy 163.83 177.8)
		)
		(stroke
			(width 0)
			(type default)
		)
	)
	(wire
		(pts
			(xy 233.68 116.84) (xy 254 116.84)
		)
		(stroke
			(width 0)
			(type default)
		)
	)
	(wire
		(pts
			(xy 148.59 78.74) (xy 148.59 81.28)
		)
		(stroke
			(width 0)
			(type default)
		)
	)
	(wire
		(pts
			(xy 119.38 40.64) (xy 128.27 40.64)
		)
		(stroke
			(width 0)
			(type default)
		)
	)
	(bus
		(pts
			(xy 304.8 119.38) (xy 304.8 121.92)
		)
		(stroke
			(width 0)
			(type default)
		)
	)
	(wire
		(pts
			(xy 233.68 114.3) (xy 274.32 114.3)
		)
		(stroke
			(width 0)
			(type default)
		)
	)
	(wire
		(pts
			(xy 132.08 243.84) (xy 132.08 246.38)
		)
		(stroke
			(width 0)
			(type default)
		)
	)
	(wire
		(pts
			(xy 165.1 99.06) (xy 187.96 99.06)
		)
		(stroke
			(width 0)
			(type default)
		)
	)
	(wire
		(pts
			(xy 118.11 99.06) (xy 118.11 96.52)
		)
		(stroke
			(width 0)
			(type default)
		)
	)
	(wire
		(pts
			(xy 180.34 55.88) (xy 180.34 78.74)
		)
		(stroke
			(width 0)
			(type default)
		)
	)
	(wire
		(pts
			(xy 92.71 58.42) (xy 130.81 58.42)
		)
		(stroke
			(width 0)
			(type default)
		)
	)
	(wire
		(pts
			(xy 149.86 223.52) (xy 149.86 238.76)
		)
		(stroke
			(width 0)
			(type default)
		)
	)
	(wire
		(pts
			(xy 50.8 229.87) (xy 53.34 229.87)
		)
		(stroke
			(width 0)
			(type default)
		)
	)
	(wire
		(pts
			(xy 67.31 213.36) (xy 62.23 213.36)
		)
		(stroke
			(width 0)
			(type default)
		)
	)
	(wire
		(pts
			(xy 67.31 185.42) (xy 69.85 185.42)
		)
		(stroke
			(width 0)
			(type default)
		)
	)
	(wire
		(pts
			(xy 128.27 160.02) (xy 151.13 160.02)
		)
		(stroke
			(width 0)
			(type default)
		)
	)
	(wire
		(pts
			(xy 146.05 109.22) (xy 187.96 109.22)
		)
		(stroke
			(width 0)
			(type default)
		)
	)
	(wire
		(pts
			(xy 241.3 157.48) (xy 241.3 160.02)
		)
		(stroke
			(width 0)
			(type default)
		)
	)
	(wire
		(pts
			(xy 110.49 119.38) (xy 114.3 119.38)
		)
		(stroke
			(width 0)
			(type default)
		)
	)
	(wire
		(pts
			(xy 97.79 171.45) (xy 97.79 168.91)
		)
		(stroke
			(width 0)
			(type default)
		)
	)
	(wire
		(pts
			(xy 64.77 121.92) (xy 62.23 121.92)
		)
		(stroke
			(width 0)
			(type default)
		)
	)
	(wire
		(pts
			(xy 274.32 116.84) (xy 274.32 124.46)
		)
		(stroke
			(width 0)
			(type default)
		)
	)
	(wire
		(pts
			(xy 58.42 232.41) (xy 55.88 232.41)
		)
		(stroke
			(width 0)
			(type default)
		)
	)
	(wire
		(pts
			(xy 167.64 96.52) (xy 187.96 96.52)
		)
		(stroke
			(width 0)
			(type default)
		)
	)
	(wire
		(pts
			(xy 182.88 53.34) (xy 182.88 76.2)
		)
		(stroke
			(width 0)
			(type default)
		)
	)
	(wire
		(pts
			(xy 233.68 104.14) (xy 265.43 104.14)
		)
		(stroke
			(width 0)
			(type default)
		)
	)
	(wire
		(pts
			(xy 170.18 91.44) (xy 187.96 91.44)
		)
		(stroke
			(width 0)
			(type default)
		)
	)
	(wire
		(pts
			(xy 274.32 114.3) (xy 302.26 114.3)
		)
		(stroke
			(width 0)
			(type default)
		)
	)
	(wire
		(pts
			(xy 245.11 147.32) (xy 245.11 149.86)
		)
		(stroke
			(width 0)
			(type default)
		)
	)
	(wire
		(pts
			(xy 135.89 96.52) (xy 146.05 96.52)
		)
		(stroke
			(width 0)
			(type default)
		)
	)
	(wire
		(pts
			(xy 110.49 40.64) (xy 110.49 43.18)
		)
		(stroke
			(width 0)
			(type default)
		)
	)
	(wire
		(pts
			(xy 110.49 48.26) (xy 110.49 71.12)
		)
		(stroke
			(width 0)
			(type default)
		)
	)
	(wire
		(pts
			(xy 96.52 220.98) (xy 96.52 223.52)
		)
		(stroke
			(width 0)
			(type default)
		)
	)
	(wire
		(pts
			(xy 69.85 234.95) (xy 67.31 234.95)
		)
		(stroke
			(width 0)
			(type default)
		)
	)
	(wire
		(pts
			(xy 256.54 101.6) (xy 302.26 101.6)
		)
		(stroke
			(width 0)
			(type default)
		)
	)
	(wire
		(pts
			(xy 245.11 149.86) (xy 241.3 149.86)
		)
		(stroke
			(width 0)
			(type default)
		)
	)
	(wire
		(pts
			(xy 92.71 71.12) (xy 110.49 71.12)
		)
		(stroke
			(width 0)
			(type default)
		)
	)
	(wire
		(pts
			(xy 53.34 215.9) (xy 53.34 213.36)
		)
		(stroke
			(width 0)
			(type default)
		)
	)
	(wire
		(pts
			(xy 137.16 63.5) (xy 172.72 63.5)
		)
		(stroke
			(width 0)
			(type default)
		)
	)
	(wire
		(pts
			(xy 97.79 179.07) (xy 97.79 181.61)
		)
		(stroke
			(width 0)
			(type default)
		)
	)
	(wire
		(pts
			(xy 167.64 68.58) (xy 167.64 96.52)
		)
		(stroke
			(width 0)
			(type default)
		)
	)
	(wire
		(pts
			(xy 118.11 96.52) (xy 127 96.52)
		)
		(stroke
			(width 0)
			(type default)
		)
	)
	(wire
		(pts
			(xy 106.68 215.9) (xy 106.68 213.36)
		)
		(stroke
			(width 0)
			(type default)
		)
	)
	(wire
		(pts
			(xy 233.68 78.74) (xy 237.49 78.74)
		)
		(stroke
			(width 0)
			(type default)
		)
	)
	(wire
		(pts
			(xy 238.76 208.28) (xy 267.97 208.28)
		)
		(stroke
			(width 0)
			(type default)
		)
	)
	(bus
		(pts
			(xy 304.8 121.92) (xy 304.8 124.46)
		)
		(stroke
			(width 0)
			(type default)
		)
	)
	(wire
		(pts
			(xy 185.42 73.66) (xy 187.96 73.66)
		)
		(stroke
			(width 0)
			(type default)
		)
	)
	(wire
		(pts
			(xy 114.3 215.9) (xy 114.3 229.87)
		)
		(stroke
			(width 0)
			(type default)
		)
	)
	(wire
		(pts
			(xy 233.68 119.38) (xy 302.26 119.38)
		)
		(stroke
			(width 0)
			(type default)
		)
	)
	(wire
		(pts
			(xy 35.56 121.92) (xy 44.45 121.92)
		)
		(stroke
			(width 0)
			(type default)
		)
	)
	(wire
		(pts
			(xy 130.81 58.42) (xy 153.67 58.42)
		)
		(stroke
			(width 0)
			(type default)
		)
	)
	(wire
		(pts
			(xy 170.18 231.14) (xy 182.88 231.14)
		)
		(stroke
			(width 0)
			(type default)
		)
	)
	(wire
		(pts
			(xy 180.34 78.74) (xy 187.96 78.74)
		)
		(stroke
			(width 0)
			(type default)
		)
	)
	(wire
		(pts
			(xy 110.49 38.1) (xy 110.49 40.64)
		)
		(stroke
			(width 0)
			(type default)
		)
	)
	(wire
		(pts
			(xy 110.49 96.52) (xy 110.49 99.06)
		)
		(stroke
			(width 0)
			(type default)
		)
	)
	(wire
		(pts
			(xy 135.89 129.54) (xy 135.89 132.08)
		)
		(stroke
			(width 0)
			(type default)
		)
	)
	(wire
		(pts
			(xy 57.15 104.14) (xy 44.45 104.14)
		)
		(stroke
			(width 0)
			(type default)
		)
	)
	(wire
		(pts
			(xy 233.68 73.66) (xy 237.49 73.66)
		)
		(stroke
			(width 0)
			(type default)
		)
	)
	(wire
		(pts
			(xy 92.71 50.8) (xy 148.59 50.8)
		)
		(stroke
			(width 0)
			(type default)
		)
	)
	(wire
		(pts
			(xy 64.77 104.14) (xy 64.77 109.22)
		)
		(stroke
			(width 0)
			(type default)
		)
	)
	(wire
		(pts
			(xy 274.32 86.36) (xy 274.32 88.9)
		)
		(stroke
			(width 0)
			(type default)
		)
	)
	(wire
		(pts
			(xy 274.32 96.52) (xy 274.32 114.3)
		)
		(stroke
			(width 0)
			(type default)
		)
	)
	(wire
		(pts
			(xy 130.81 73.66) (xy 130.81 58.42)
		)
		(stroke
			(width 0)
			(type default)
		)
	)
	(wire
		(pts
			(xy 124.46 129.54) (xy 124.46 132.08)
		)
		(stroke
			(width 0)
			(type default)
		)
	)
	(bus
		(pts
			(xy 304.8 124.46) (xy 304.8 127)
		)
		(stroke
			(width 0)
			(type default)
		)
	)
	(wire
		(pts
			(xy 110.49 104.14) (xy 110.49 114.3)
		)
		(stroke
			(width 0)
			(type default)
		)
	)
	(wire
		(pts
			(xy 44.45 104.14) (xy 41.91 104.14)
		)
		(stroke
			(width 0)
			(type default)
		)
	)
	(wire
		(pts
			(xy 128.27 66.04) (xy 153.67 66.04)
		)
		(stroke
			(width 0)
			(type default)
		)
	)
	(wire
		(pts
			(xy 154.94 106.68) (xy 187.96 106.68)
		)
		(stroke
			(width 0)
			(type default)
		)
	)
	(wire
		(pts
			(xy 113.03 162.56) (xy 113.03 158.75)
		)
		(stroke
			(width 0)
			(type default)
		)
	)
	(wire
		(pts
			(xy 172.72 175.26) (xy 172.72 177.8)
		)
		(stroke
			(width 0)
			(type default)
		)
	)
	(wire
		(pts
			(xy 265.43 96.52) (xy 265.43 104.14)
		)
		(stroke
			(width 0)
			(type default)
		)
	)
	(wire
		(pts
			(xy 69.85 232.41) (xy 63.5 232.41)
		)
		(stroke
			(width 0)
			(type default)
		)
	)
	(wire
		(pts
			(xy 62.23 179.07) (xy 62.23 181.61)
		)
		(stroke
			(width 0)
			(type default)
		)
	)
	(wire
		(pts
			(xy 160.02 190.5) (xy 182.88 190.5)
		)
		(stroke
			(width 0)
			(type default)
		)
	)
	(wire
		(pts
			(xy 67.31 171.45) (xy 62.23 171.45)
		)
		(stroke
			(width 0)
			(type default)
		)
	)
	(wire
		(pts
			(xy 64.77 124.46) (xy 62.23 124.46)
		)
		(stroke
			(width 0)
			(type default)
		)
	)
	(wire
		(pts
			(xy 241.3 160.02) (xy 238.76 160.02)
		)
		(stroke
			(width 0)
			(type default)
		)
	)
	(wire
		(pts
			(xy 242.57 205.74) (xy 242.57 210.82)
		)
		(stroke
			(width 0)
			(type default)
		)
	)
	(wire
		(pts
			(xy 167.64 167.64) (xy 182.88 167.64)
		)
		(stroke
			(width 0)
			(type default)
		)
	)
	(wire
		(pts
			(xy 158.75 66.04) (xy 170.18 66.04)
		)
		(stroke
			(width 0)
			(type default)
		)
	)
	(wire
		(pts
			(xy 242.57 218.44) (xy 242.57 246.38)
		)
		(stroke
			(width 0)
			(type default)
		)
	)
	(wire
		(pts
			(xy 114.3 119.38) (xy 114.3 124.46)
		)
		(stroke
			(width 0)
			(type default)
		)
	)
	(wire
		(pts
			(xy 114.3 119.38) (xy 124.46 119.38)
		)
		(stroke
			(width 0)
			(type default)
		)
	)
	(wire
		(pts
			(xy 158.75 71.12) (xy 165.1 71.12)
		)
		(stroke
			(width 0)
			(type default)
		)
	)
	(wire
		(pts
			(xy 132.08 210.82) (xy 132.08 238.76)
		)
		(stroke
			(width 0)
			(type default)
		)
	)
	(wire
		(pts
			(xy 233.68 99.06) (xy 247.65 99.06)
		)
		(stroke
			(width 0)
			(type default)
		)
	)
	(wire
		(pts
			(xy 135.89 116.84) (xy 135.89 104.14)
		)
		(stroke
			(width 0)
			(type default)
		)
	)
	(wire
		(pts
			(xy 128.27 158.75) (xy 128.27 160.02)
		)
		(stroke
			(width 0)
			(type default)
		)
	)
	(wire
		(pts
			(xy 163.83 185.42) (xy 163.83 187.96)
		)
		(stroke
			(width 0)
			(type default)
		)
	)
	(wire
		(pts
			(xy 163.83 177.8) (xy 172.72 177.8)
		)
		(stroke
			(width 0)
			(type default)
		)
	)
	(wire
		(pts
			(xy 92.71 227.33) (xy 90.17 227.33)
		)
		(stroke
			(width 0)
			(type default)
		)
	)
	(wire
		(pts
			(xy 67.31 171.45) (xy 67.31 185.42)
		)
		(stroke
			(width 0)
			(type default)
		)
	)
	(wire
		(pts
			(xy 154.94 106.68) (xy 154.94 124.46)
		)
		(stroke
			(width 0)
			(type default)
		)
	)
	(wire
		(pts
			(xy 245.11 162.56) (xy 247.65 162.56)
		)
		(stroke
			(width 0)
			(type default)
		)
	)
	(wire
		(pts
			(xy 55.88 232.41) (xy 55.88 237.49)
		)
		(stroke
			(width 0)
			(type default)
		)
	)
	(wire
		(pts
			(xy 148.59 50.8) (xy 148.59 73.66)
		)
		(stroke
			(width 0)
			(type default)
		)
	)
	(wire
		(pts
			(xy 156.21 162.56) (xy 182.88 162.56)
		)
		(stroke
			(width 0)
			(type default)
		)
	)
	(wire
		(pts
			(xy 182.88 53.34) (xy 158.75 53.34)
		)
		(stroke
			(width 0)
			(type default)
		)
	)
	(wire
		(pts
			(xy 146.05 104.14) (xy 146.05 109.22)
		)
		(stroke
			(width 0)
			(type default)
		)
	)
	(wire
		(pts
			(xy 245.11 149.86) (xy 245.11 152.4)
		)
		(stroke
			(width 0)
			(type default)
		)
	)
	(wire
		(pts
			(xy 158.75 236.22) (xy 158.75 246.38)
		)
		(stroke
			(width 0)
			(type default)
		)
	)
	(wire
		(pts
			(xy 62.23 220.98) (xy 62.23 223.52)
		)
		(stroke
			(width 0)
			(type default)
		)
	)
	(wire
		(pts
			(xy 92.71 185.42) (xy 90.17 185.42)
		)
		(stroke
			(width 0)
			(type default)
		)
	)
	(wire
		(pts
			(xy 247.65 88.9) (xy 256.54 88.9)
		)
		(stroke
			(width 0)
			(type default)
		)
	)
	(wire
		(pts
			(xy 113.03 158.75) (xy 128.27 158.75)
		)
		(stroke
			(width 0)
			(type default)
		)
	)
	(wire
		(pts
			(xy 175.26 60.96) (xy 121.92 60.96)
		)
		(stroke
			(width 0)
			(type default)
		)
	)
	(wire
		(pts
			(xy 106.68 220.98) (xy 106.68 229.87)
		)
		(stroke
			(width 0)
			(type default)
		)
	)
	(wire
		(pts
			(xy 154.94 96.52) (xy 146.05 96.52)
		)
		(stroke
			(width 0)
			(type default)
		)
	)
	(wire
		(pts
			(xy 128.27 40.64) (xy 137.16 40.64)
		)
		(stroke
			(width 0)
			(type default)
		)
	)
	(wire
		(pts
			(xy 110.49 93.98) (xy 110.49 96.52)
		)
		(stroke
			(width 0)
			(type default)
		)
	)
	(wire
		(pts
			(xy 67.31 234.95) (xy 67.31 237.49)
		)
		(stroke
			(width 0)
			(type default)
		)
	)
	(wire
		(pts
			(xy 154.94 129.54) (xy 154.94 132.08)
		)
		(stroke
			(width 0)
			(type default)
		)
	)
	(wire
		(pts
			(xy 160.02 185.42) (xy 160.02 190.5)
		)
		(stroke
			(width 0)
			(type default)
		)
	)
	(wire
		(pts
			(xy 53.34 213.36) (xy 62.23 213.36)
		)
		(stroke
			(width 0)
			(type default)
		)
	)
	(wire
		(pts
			(xy 149.86 243.84) (xy 149.86 246.38)
		)
		(stroke
			(width 0)
			(type default)
		)
	)
	(wire
		(pts
			(xy 90.17 193.04) (xy 92.71 193.04)
		)
		(stroke
			(width 0)
			(type default)
		)
	)
	(wire
		(pts
			(xy 154.94 104.14) (xy 154.94 106.68)
		)
		(stroke
			(width 0)
			(type default)
		)
	)
	(wire
		(pts
			(xy 90.17 187.96) (xy 163.83 187.96)
		)
		(stroke
			(width 0)
			(type default)
		)
	)
	(wire
		(pts
			(xy 123.19 208.28) (xy 123.19 246.38)
		)
		(stroke
			(width 0)
			(type default)
		)
	)
	(wire
		(pts
			(xy 146.05 129.54) (xy 146.05 132.08)
		)
		(stroke
			(width 0)
			(type default)
		)
	)
	(wire
		(pts
			(xy 92.71 213.36) (xy 96.52 213.36)
		)
		(stroke
			(width 0)
			(type default)
		)
	)
	(wire
		(pts
			(xy 153.67 53.34) (xy 146.05 53.34)
		)
		(stroke
			(width 0)
			(type default)
		)
	)
	(wire
		(pts
			(xy 33.02 101.6) (xy 33.02 104.14)
		)
		(stroke
			(width 0)
			(type default)
		)
	)
	(wire
		(pts
			(xy 238.76 218.44) (xy 242.57 218.44)
		)
		(stroke
			(width 0)
			(type default)
		)
	)
	(wire
		(pts
			(xy 67.31 227.33) (xy 69.85 227.33)
		)
		(stroke
			(width 0)
			(type default)
		)
	)
	(wire
		(pts
			(xy 256.54 96.52) (xy 256.54 101.6)
		)
		(stroke
			(width 0)
			(type default)
		)
	)
	(wire
		(pts
			(xy 62.23 171.45) (xy 62.23 173.99)
		)
		(stroke
			(width 0)
			(type default)
		)
	)
	(wire
		(pts
			(xy 149.86 223.52) (xy 182.88 223.52)
		)
		(stroke
			(width 0)
			(type default)
		)
	)
	(wire
		(pts
			(xy 118.11 121.92) (xy 118.11 104.14)
		)
		(stroke
			(width 0)
			(type default)
		)
	)
	(wire
		(pts
			(xy 137.16 172.72) (xy 137.16 175.26)
		)
		(stroke
			(width 0)
			(type default)
		)
	)
	(wire
		(pts
			(xy 135.89 99.06) (xy 135.89 96.52)
		)
		(stroke
			(width 0)
			(type default)
		)
	)
	(wire
		(pts
			(xy 119.38 48.26) (xy 119.38 68.58)
		)
		(stroke
			(width 0)
			(type default)
		)
	)
	(wire
		(pts
			(xy 172.72 193.04) (xy 182.88 193.04)
		)
		(stroke
			(width 0)
			(type default)
		)
	)
	(wire
		(pts
			(xy 67.31 213.36) (xy 67.31 227.33)
		)
		(stroke
			(width 0)
			(type default)
		)
	)
	(wire
		(pts
			(xy 106.68 229.87) (xy 90.17 229.87)
		)
		(stroke
			(width 0)
			(type default)
		)
	)
	(wire
		(pts
			(xy 170.18 226.06) (xy 182.88 226.06)
		)
		(stroke
			(width 0)
			(type default)
		)
	)
	(bus
		(pts
			(xy 304.8 104.14) (xy 304.8 106.68)
		)
		(stroke
			(width 0)
			(type default)
		)
	)
	(wire
		(pts
			(xy 170.18 228.6) (xy 182.88 228.6)
		)
		(stroke
			(width 0)
			(type default)
		)
	)
	(wire
		(pts
			(xy 238.76 215.9) (xy 242.57 215.9)
		)
		(stroke
			(width 0)
			(type default)
		)
	)
	(wire
		(pts
			(xy 170.18 66.04) (xy 170.18 91.44)
		)
		(stroke
			(width 0)
			(type default)
		)
	)
	(wire
		(pts
			(xy 92.71 60.96) (xy 121.92 60.96)
		)
		(stroke
			(width 0)
			(type default)
		)
	)
	(wire
		(pts
			(xy 67.31 210.82) (xy 67.31 213.36)
		)
		(stroke
			(width 0)
			(type default)
		)
	)
	(wire
		(pts
			(xy 128.27 160.02) (xy 128.27 167.64)
		)
		(stroke
			(width 0)
			(type default)
		)
	)
	(wire
		(pts
			(xy 110.49 114.3) (xy 187.96 114.3)
		)
		(stroke
			(width 0)
			(type default)
		)
	)
	(wire
		(pts
			(xy 182.88 76.2) (xy 187.96 76.2)
		)
		(stroke
			(width 0)
			(type default)
		)
	)
	(wire
		(pts
			(xy 146.05 109.22) (xy 146.05 124.46)
		)
		(stroke
			(width 0)
			(type default)
		)
	)
	(wire
		(pts
			(xy 119.38 167.64) (xy 119.38 175.26)
		)
		(stroke
			(width 0)
			(type default)
		)
	)
	(wire
		(pts
			(xy 139.7 73.66) (xy 139.7 55.88)
		)
		(stroke
			(width 0)
			(type default)
		)
	)
	(wire
		(pts
			(xy 62.23 213.36) (xy 62.23 215.9)
		)
		(stroke
			(width 0)
			(type default)
		)
	)
	(wire
		(pts
			(xy 44.45 93.98) (xy 44.45 96.52)
		)
		(stroke
			(width 0)
			(type default)
		)
	)
	(wire
		(pts
			(xy 33.02 104.14) (xy 41.91 104.14)
		)
		(stroke
			(width 0)
			(type default)
		)
	)
	(wire
		(pts
			(xy 92.71 185.42) (xy 92.71 193.04)
		)
		(stroke
			(width 0)
			(type default)
		)
	)
	(wire
		(pts
			(xy 44.45 118.11) (xy 41.91 118.11)
		)
		(stroke
			(width 0)
			(type default)
		)
	)
	(wire
		(pts
			(xy 106.68 229.87) (xy 114.3 229.87)
		)
		(stroke
			(width 0)
			(type default)
		)
	)
	(wire
		(pts
			(xy 245.11 162.56) (xy 238.76 162.56)
		)
		(stroke
			(width 0)
			(type default)
		)
	)
	(wire
		(pts
			(xy 177.8 58.42) (xy 158.75 58.42)
		)
		(stroke
			(width 0)
			(type default)
		)
	)
	(wire
		(pts
			(xy 175.26 83.82) (xy 187.96 83.82)
		)
		(stroke
			(width 0)
			(type default)
		)
	)
	(wire
		(pts
			(xy 267.97 204.47) (xy 267.97 208.28)
		)
		(stroke
			(width 0)
			(type default)
		)
	)
	(wire
		(pts
			(xy 259.08 116.84) (xy 274.32 116.84)
		)
		(stroke
			(width 0)
			(type default)
		)
	)
	(wire
		(pts
			(xy 148.59 167.64) (xy 148.59 165.1)
		)
		(stroke
			(width 0)
			(type default)
		)
	)
	(wire
		(pts
			(xy 154.94 99.06) (xy 154.94 96.52)
		)
		(stroke
			(width 0)
			(type default)
		)
	)
	(wire
		(pts
			(xy 265.43 88.9) (xy 265.43 91.44)
		)
		(stroke
			(width 0)
			(type default)
		)
	)
	(bus
		(pts
			(xy 304.8 106.68) (xy 304.8 109.22)
		)
		(stroke
			(width 0)
			(type default)
		)
	)
	(wire
		(pts
			(xy 72.39 119.38) (xy 105.41 119.38)
		)
		(stroke
			(width 0)
			(type default)
		)
	)
	(wire
		(pts
			(xy 185.42 50.8) (xy 185.42 73.66)
		)
		(stroke
			(width 0)
			(type default)
		)
	)
	(wire
		(pts
			(xy 110.49 96.52) (xy 118.11 96.52)
		)
		(stroke
			(width 0)
			(type default)
		)
	)
	(wire
		(pts
			(xy 33.02 106.68) (xy 33.02 104.14)
		)
		(stroke
			(width 0)
			(type default)
		)
	)
	(wire
		(pts
			(xy 119.38 43.18) (xy 119.38 40.64)
		)
		(stroke
			(width 0)
			(type default)
		)
	)
	(wire
		(pts
			(xy 110.49 40.64) (xy 119.38 40.64)
		)
		(stroke
			(width 0)
			(type default)
		)
	)
	(wire
		(pts
			(xy 172.72 177.8) (xy 172.72 180.34)
		)
		(stroke
			(width 0)
			(type default)
		)
	)
	(wire
		(pts
			(xy 121.92 78.74) (xy 121.92 81.28)
		)
		(stroke
			(width 0)
			(type default)
		)
	)
	(wire
		(pts
			(xy 139.7 78.74) (xy 139.7 81.28)
		)
		(stroke
			(width 0)
			(type default)
		)
	)
	(wire
		(pts
			(xy 121.92 60.96) (xy 121.92 73.66)
		)
		(stroke
			(width 0)
			(type default)
		)
	)
	(wire
		(pts
			(xy 139.7 55.88) (xy 180.34 55.88)
		)
		(stroke
			(width 0)
			(type default)
		)
	)
	(wire
		(pts
			(xy 148.59 165.1) (xy 182.88 165.1)
		)
		(stroke
			(width 0)
			(type default)
		)
	)
	(wire
		(pts
			(xy 137.16 162.56) (xy 137.16 167.64)
		)
		(stroke
			(width 0)
			(type default)
		)
	)
	(wire
		(pts
			(xy 137.16 162.56) (xy 151.13 162.56)
		)
		(stroke
			(width 0)
			(type default)
		)
	)
	(wire
		(pts
			(xy 156.21 160.02) (xy 182.88 160.02)
		)
		(stroke
			(width 0)
			(type default)
		)
	)
	(wire
		(pts
			(xy 64.77 121.92) (xy 118.11 121.92)
		)
		(stroke
			(width 0)
			(type default)
		)
	)
	(wire
		(pts
			(xy 41.91 118.11) (xy 41.91 104.14)
		)
		(stroke
			(width 0)
			(type default)
		)
	)
	(wire
		(pts
			(xy 160.02 180.34) (xy 160.02 177.8)
		)
		(stroke
			(width 0)
			(type default)
		)
	)
	(wire
		(pts
			(xy 106.68 210.82) (xy 106.68 213.36)
		)
		(stroke
			(width 0)
			(type default)
		)
	)
	(wire
		(pts
			(xy 119.38 68.58) (xy 167.64 68.58)
		)
		(stroke
			(width 0)
			(type default)
		)
	)
	(wire
		(pts
			(xy 92.71 213.36) (xy 92.71 227.33)
		)
		(stroke
			(width 0)
			(type default)
		)
	)
	(wire
		(pts
			(xy 127 104.14) (xy 127 119.38)
		)
		(stroke
			(width 0)
			(type default)
		)
	)
	(wire
		(pts
			(xy 177.8 58.42) (xy 177.8 81.28)
		)
		(stroke
			(width 0)
			(type default)
		)
	)
	(bus
		(pts
			(xy 307.34 129.54) (xy 309.88 129.54)
		)
		(stroke
			(width 0)
			(type default)
		)
	)
	(wire
		(pts
			(xy 64.77 132.08) (xy 64.77 124.46)
		)
		(stroke
			(width 0)
			(type default)
		)
	)
	(wire
		(pts
			(xy 113.03 162.56) (xy 115.57 162.56)
		)
		(stroke
			(width 0)
			(type default)
		)
	)
	(wire
		(pts
			(xy 57.15 93.98) (xy 57.15 104.14)
		)
		(stroke
			(width 0)
			(type default)
		)
	)
	(wire
		(pts
			(xy 241.3 160.02) (xy 247.65 160.02)
		)
		(stroke
			(width 0)
			(type default)
		)
	)
	(wire
		(pts
			(xy 242.57 210.82) (xy 242.57 213.36)
		)
		(stroke
			(width 0)
			(type default)
		)
	)
	(wire
		(pts
			(xy 175.26 60.96) (xy 175.26 83.82)
		)
		(stroke
			(width 0)
			(type default)
		)
	)
	(wire
		(pts
			(xy 128.27 172.72) (xy 128.27 175.26)
		)
		(stroke
			(width 0)
			(type default)
		)
	)
	(wire
		(pts
			(xy 69.85 193.04) (xy 67.31 193.04)
		)
		(stroke
			(width 0)
			(type default)
		)
	)
	(wire
		(pts
			(xy 135.89 116.84) (xy 135.89 124.46)
		)
		(stroke
			(width 0)
			(type default)
		)
	)
	(wire
		(pts
			(xy 97.79 171.45) (xy 97.79 173.99)
		)
		(stroke
			(width 0)
			(type default)
		)
	)
	(wire
		(pts
			(xy 127 96.52) (xy 127 99.06)
		)
		(stroke
			(width 0)
			(type default)
		)
	)
	(wire
		(pts
			(xy 123.19 162.56) (xy 137.16 162.56)
		)
		(stroke
			(width 0)
			(type default)
		)
	)
	(wire
		(pts
			(xy 158.75 236.22) (xy 182.88 236.22)
		)
		(stroke
			(width 0)
			(type default)
		)
	)
	(wire
		(pts
			(xy 247.65 91.44) (xy 247.65 88.9)
		)
		(stroke
			(width 0)
			(type default)
		)
	)
	(wire
		(pts
			(xy 146.05 48.26) (xy 146.05 53.34)
		)
		(stroke
			(width 0)
			(type default)
		)
	)
	(wire
		(pts
			(xy 238.76 213.36) (xy 242.57 213.36)
		)
		(stroke
			(width 0)
			(type default)
		)
	)
	(wire
		(pts
			(xy 148.59 172.72) (xy 148.59 175.26)
		)
		(stroke
			(width 0)
			(type default)
		)
	)
	(wire
		(pts
			(xy 96.52 213.36) (xy 96.52 215.9)
		)
		(stroke
			(width 0)
			(type default)
		)
	)
	(wire
		(pts
			(xy 274.32 88.9) (xy 265.43 88.9)
		)
		(stroke
			(width 0)
			(type default)
		)
	)
	(wire
		(pts
			(xy 163.83 187.96) (xy 182.88 187.96)
		)
		(stroke
			(width 0)
			(type default)
		)
	)
	(wire
		(pts
			(xy 92.71 227.33) (xy 92.71 234.95)
		)
		(stroke
			(width 0)
			(type default)
		)
	)
	(wire
		(pts
			(xy 92.71 55.88) (xy 139.7 55.88)
		)
		(stroke
			(width 0)
			(type default)
		)
	)
	(label "XTAL_BYPASS"
		(at 180.34 165.1 180)
		(effects
			(font
				(size 1.27 1.27)
			)
			(justify right bottom)
		)
	)
	(label "50MHZ_XTAL.+"
		(at 180.34 160.02 180)
		(effects
			(font
				(size 1.27 1.27)
			)
			(justify right bottom)
		)
	)
	(label "PHY_TDO"
		(at 180.34 233.68 180)
		(effects
			(font
				(size 1.27 1.27)
			)
			(justify right bottom)
		)
	)
	(label "NCSI.TX_EN"
		(at 93.98 60.96 0)
		(effects
			(font
				(size 1.27 1.27)
			)
			(justify left bottom)
		)
	)
	(label "NCSI.TXD_0"
		(at 93.98 63.5 0)
		(effects
			(font
				(size 1.27 1.27)
			)
			(justify left bottom)
		)
	)
	(label "AUX_PWR"
		(at 185.42 116.84 180)
		(effects
			(font
				(size 1.27 1.27)
			)
			(justify right bottom)
		)
	)
	(label "RSVD_J11_VSS"
		(at 180.34 210.82 180)
		(effects
			(font
				(size 1.27 1.27)
			)
			(justify right bottom)
		)
	)
	(label "SMBus.SCL"
		(at 290.83 101.6 0)
		(effects
			(font
				(size 1.27 1.27)
			)
			(justify left bottom)
		)
	)
	(label "NCSI.TXD_1"
		(at 93.98 68.58 0)
		(effects
			(font
				(size 1.27 1.27)
			)
			(justify left bottom)
		)
	)
	(label "~{PHY_TRST}"
		(at 180.34 223.52 180)
		(effects
			(font
				(size 1.27 1.27)
			)
			(justify right bottom)
		)
	)
	(label "GPIO5_POR_BYPASS"
		(at 72.39 119.38 0)
		(effects
			(font
				(size 1.27 1.27)
			)
			(justify left bottom)
		)
	)
	(label "PHY_TMS"
		(at 180.34 228.6 180)
		(effects
			(font
				(size 1.27 1.27)
			)
			(justify right bottom)
		)
	)
	(label "NCSI.RXD_1"
		(at 93.98 71.12 0)
		(effects
			(font
				(size 1.27 1.27)
			)
			(justify left bottom)
		)
	)
	(label "MDIO_I2C.MDIO"
		(at 45.72 190.5 0)
		(effects
			(font
				(size 1.27 1.27)
			)
			(justify left bottom)
		)
	)
	(label "NCSI.CRS_DV"
		(at 93.98 58.42 0)
		(effects
			(font
				(size 1.27 1.27)
			)
			(justify left bottom)
		)
	)
	(label "REFCLK_SEL"
		(at 180.34 167.64 180)
		(effects
			(font
				(size 1.27 1.27)
			)
			(justify right bottom)
		)
	)
	(label "PHY_TDI"
		(at 180.34 231.14 180)
		(effects
			(font
				(size 1.27 1.27)
			)
			(justify right bottom)
		)
	)
	(label "FLSH_SCK"
		(at 236.22 116.84 0)
		(effects
			(font
				(size 1.27 1.27)
			)
			(justify left bottom)
		)
	)
	(label "MDIO_I2C.MDC"
		(at 45.72 187.96 0)
		(effects
			(font
				(size 1.27 1.27)
			)
			(justify left bottom)
		)
	)
	(label "50MHZ_XTAL_R.+"
		(at 146.05 160.02 180)
		(effects
			(font
				(size 1.27 1.27)
			)
			(justify right bottom)
		)
	)
	(label "~{PCI_DIS}"
		(at 185.42 109.22 180)
		(effects
			(font
				(size 1.27 1.27)
			)
			(justify right bottom)
		)
	)
	(label "MAIN_PWR_OK"
		(at 185.42 114.3 180)
		(effects
			(font
				(size 1.27 1.27)
			)
			(justify right bottom)
		)
	)
	(label "FLASH.MISO"
		(at 290.83 121.92 0)
		(effects
			(font
				(size 1.27 1.27)
			)
			(justify left bottom)
		)
	)
	(label "RSVDK40_1P88V"
		(at 245.11 208.28 0)
		(effects
			(font
				(size 1.27 1.27)
			)
			(justify left bottom)
		)
	)
	(label "POR_BYPASS"
		(at 185.42 119.38 180)
		(effects
			(font
				(size 1.27 1.27)
			)
			(justify right bottom)
		)
	)
	(label "SMBus.SDA"
		(at 290.83 104.14 0)
		(effects
			(font
				(size 1.27 1.27)
			)
			(justify left bottom)
		)
	)
	(label "MDIO.MDC"
		(at 101.6 187.96 0)
		(effects
			(font
				(size 1.27 1.27)
			)
			(justify left bottom)
		)
	)
	(label "FLASH.~{CE}"
		(at 290.83 114.3 0)
		(effects
			(font
				(size 1.27 1.27)
			)
			(justify left bottom)
		)
	)
	(label "RSVDL33"
		(at 182.88 193.04 180)
		(effects
			(font
				(size 1.27 1.27)
			)
			(justify right bottom)
		)
	)
	(label "MDIO.MDIO"
		(at 101.6 190.5 0)
		(effects
			(font
				(size 1.27 1.27)
			)
			(justify left bottom)
		)
	)
	(label "PHY_TCK"
		(at 180.34 226.06 180)
		(effects
			(font
				(size 1.27 1.27)
			)
			(justify right bottom)
		)
	)
	(label "NCSI.RXD_0"
		(at 93.98 66.04 0)
		(effects
			(font
				(size 1.27 1.27)
			)
			(justify left bottom)
		)
	)
	(label "LAN_PWR_GOOD"
		(at 185.42 121.92 180)
		(effects
			(font
				(size 1.27 1.27)
			)
			(justify right bottom)
		)
	)
	(label "~{SMBALRT}"
		(at 236.22 99.06 0)
		(effects
			(font
				(size 1.27 1.27)
			)
			(justify left bottom)
		)
	)
	(label "NCSI.REF_CLK"
		(at 93.98 55.88 0)
		(effects
			(font
				(size 1.27 1.27)
			)
			(justify left bottom)
		)
	)
	(label "50MHZ_XTAL.-"
		(at 180.34 162.56 180)
		(effects
			(font
				(size 1.27 1.27)
			)
			(justify right bottom)
		)
	)
	(label "FLASH.MOSI"
		(at 290.83 119.38 0)
		(effects
			(font
				(size 1.27 1.27)
			)
			(justify left bottom)
		)
	)
	(label "NCSI.ARB_OUT"
		(at 93.98 53.34 0)
		(effects
			(font
				(size 1.27 1.27)
			)
			(justify left bottom)
		)
	)
	(label "FLASH.CLK"
		(at 290.83 116.84 0)
		(effects
			(font
				(size 1.27 1.27)
			)
			(justify left bottom)
		)
	)
	(label "GPIO5_POR_BYPASS"
		(at 262.89 86.36 180)
		(effects
			(font
				(size 1.27 1.27)
			)
			(justify right bottom)
		)
	)
	(label "~{DEV_DIS}"
		(at 185.42 106.68 180)
		(effects
			(font
				(size 1.27 1.27)
			)
			(justify right bottom)
		)
	)
	(label "50MHZ_XTAL_R.-"
		(at 146.05 162.56 180)
		(effects
			(font
				(size 1.27 1.27)
			)
			(justify right bottom)
		)
	)
	(label "NCSI.ARB_IN"
		(at 93.98 50.8 0)
		(effects
			(font
				(size 1.27 1.27)
			)
			(justify left bottom)
		)
	)
	(label "~{PHY_RESET}"
		(at 180.34 215.9 180)
		(effects
			(font
				(size 1.27 1.27)
			)
			(justify right bottom)
		)
	)
	(hierarchical_label "FLASH{SPI}"
		(shape bidirectional)
		(at 309.88 129.54 0)
		(effects
			(font
				(size 1.27 1.27)
			)
			(justify left)
		)
	)
	(hierarchical_label "P1_INT_MLC"
		(shape output)
		(at 247.65 162.56 0)
		(effects
			(font
				(size 1.27 1.27)
			)
			(justify left)
		)
	)
	(hierarchical_label "~{PE_RST}"
		(shape input)
		(at 25.4 121.92 180)
		(effects
			(font
				(size 1.27 1.27)
			)
			(justify right)
		)
	)
	(hierarchical_label "~{P1_LINK_LESS_THAN_10G}"
		(shape output)
		(at 237.49 78.74 0)
		(effects
			(font
				(size 1.27 1.27)
			)
			(justify left)
		)
	)
	(hierarchical_label "~{PHY_RESET_3V3}"
		(shape input)
		(at 50.8 229.87 180)
		(effects
			(font
				(size 1.27 1.27)
			)
			(justify right)
		)
	)
	(hierarchical_label "~{P0_LINK_LESS_THAN_10G}"
		(shape output)
		(at 237.49 73.66 0)
		(effects
			(font
				(size 1.27 1.27)
			)
			(justify left)
		)
	)
	(hierarchical_label "SMBus{I2C}"
		(shape bidirectional)
		(at 309.88 111.76 0)
		(effects
			(font
				(size 1.27 1.27)
			)
			(justify left)
		)
	)
	(hierarchical_label "MDIO_I2C{MDIO}"
		(shape bidirectional)
		(at 36.83 198.12 180)
		(effects
			(font
				(size 1.27 1.27)
			)
			(justify right)
		)
	)
	(hierarchical_label "P0_INT_MLC"
		(shape output)
		(at 247.65 160.02 0)
		(effects
			(font
				(size 1.27 1.27)
			)
			(justify left)
		)
	)
	(symbol
		(lib_id "antmicroResistors0402:R_100k_0402")
		(at 128.27 48.26 90)
		(unit 1)
		(exclude_from_sim no)
		(in_bom yes)
		(on_board yes)
		(dnp no)
		(property "Reference" "R80"
			(at 129.794 44.45 90)
			(effects
				(font
					(size 1.27 1.27)
					(thickness 0.15)
				)
				(justify right)
			)
		)
		(property "Value" "R_100k_0402"
			(at 140.97 27.94 0)
			(effects
				(font
					(size 1.27 1.27)
					(thickness 0.15)
				)
				(justify left bottom)
				(hide yes)
			)
		)
		(property "Footprint" "antmicro-footprints:R_0402_1005Metric"
			(at 143.51 27.94 0)
			(effects
				(font
					(size 1.27 1.27)
					(thickness 0.15)
				)
				(justify left bottom)
				(hide yes)
			)
		)
		(property "Datasheet" "https://www.bourns.com/docs/product-datasheets/cr.pdf"
			(at 146.05 27.94 0)
			(effects
				(font
					(size 1.27 1.27)
					(thickness 0.15)
				)
				(justify left bottom)
				(hide yes)
			)
		)
		(property "Description" "SMD Chip Resistor, 100 kohm, ± 1%, 62.5 mW, 0402 [1005 Metric], Thick Film, General Purpose"
			(at 128.27 48.26 0)
			(effects
				(font
					(size 1.27 1.27)
				)
				(hide yes)
			)
		)
		(property "MPN" "CR0402-FX-1003GLF"
			(at 148.59 27.94 0)
			(effects
				(font
					(size 1.27 1.27)
					(thickness 0.15)
				)
				(justify left bottom)
				(hide yes)
			)
		)
		(property "Manufacturer" "Bourns"
			(at 151.13 27.94 0)
			(effects
				(font
					(size 1.27 1.27)
					(thickness 0.15)
				)
				(justify left bottom)
				(hide yes)
			)
		)
		(property "License" "Apache-2.0"
			(at 153.67 27.94 0)
			(effects
				(font
					(size 1.27 1.27)
					(thickness 0.15)
				)
				(justify left bottom)
				(hide yes)
			)
		)
		(property "Author" "Antmicro"
			(at 156.21 27.94 0)
			(effects
				(font
					(size 1.27 1.27)
					(thickness 0.15)
				)
				(justify left bottom)
				(hide yes)
			)
		)
		(property "Val" "100k"
			(at 129.794 46.99 90)
			(effects
				(font
					(size 1.27 1.27)
					(thickness 0.15)
				)
				(justify right)
			)
		)
		(property "Tolerance" "1%"
			(at 138.43 27.94 0)
			(effects
				(font
					(size 1.27 1.27)
				)
				(justify left bottom)
				(hide yes)
			)
		)
		(pin "2"
		)
		(pin "1"
		)
		(instances
			(project "OCuLink to 10GbE adapter"
				(path ""
					(reference "R80")
					(unit 1)
				)
			)
		)
	)
	(symbol
		(lib_id "antmicroCapacitors0402:C_100n_0402")
		(at 33.02 111.76 90)
		(unit 1)
		(exclude_from_sim no)
		(in_bom yes)
		(on_board yes)
		(dnp no)
		(fields_autoplaced yes)
		(property "Reference" "C198"
			(at 35.56 107.9436 90)
			(effects
				(font
					(size 1.27 1.27)
					(thickness 0.15)
				)
				(justify right)
			)
		)
		(property "Value" "C_100n_0402"
			(at 55.88 96.52 0)
			(effects
				(font
					(size 1.27 1.27)
					(thickness 0.15)
				)
				(justify left bottom)
				(hide yes)
			)
		)
		(property "Footprint" "antmicro-footprints:C_0402_1005Metric"
			(at 58.42 96.52 0)
			(effects
				(font
					(size 1.27 1.27)
					(thickness 0.15)
				)
				(justify left bottom)
				(hide yes)
			)
		)
		(property "Datasheet" "https://www.murata.com/products/productdetail?partno=GRM155R61H104KE14%23"
			(at 60.96 96.52 0)
			(effects
				(font
					(size 1.27 1.27)
					(thickness 0.15)
				)
				(justify left bottom)
				(hide yes)
			)
		)
		(property "Description" "SMD Multilayer Ceramic Capacitor, 0.1 µF, 50 V, 0402 [1005 Metric], ± 10%, X5R, GRM Series"
			(at 33.02 111.76 0)
			(effects
				(font
					(size 1.27 1.27)
				)
				(hide yes)
			)
		)
		(property "MPN" "GRM155R61H104KE14D"
			(at 63.5 96.52 0)
			(effects
				(font
					(size 1.27 1.27)
					(thickness 0.15)
				)
				(justify left bottom)
				(hide yes)
			)
		)
		(property "Val" "100n"
			(at 35.56 110.4836 90)
			(effects
				(font
					(size 1.27 1.27)
					(thickness 0.15)
				)
				(justify right)
			)
		)
		(property "Voltage" "50V"
			(at 43.18 96.52 0)
			(effects
				(font
					(size 1.27 1.27)
					(thickness 0.15)
				)
				(justify left bottom)
				(hide yes)
			)
		)
		(property "Dielectric" "X5R"
			(at 45.72 96.52 0)
			(effects
				(font
					(size 1.27 1.27)
					(thickness 0.15)
				)
				(justify left bottom)
				(hide yes)
			)
		)
		(property "Manufacturer" "Murata"
			(at 48.26 96.52 0)
			(effects
				(font
					(size 1.27 1.27)
					(thickness 0.15)
				)
				(justify left bottom)
				(hide yes)
			)
		)
		(property "License" "Apache-2.0"
			(at 50.8 96.52 0)
			(effects
				(font
					(size 1.27 1.27)
					(thickness 0.15)
				)
				(justify left bottom)
				(hide yes)
			)
		)
		(property "Author" "Antmicro"
			(at 53.34 96.52 0)
			(effects
				(font
					(size 1.27 1.27)
					(thickness 0.15)
				)
				(justify left bottom)
				(hide yes)
			)
		)
		(pin "2"
		)
		(pin "1"
		)
		(instances
			(project ""
				(path ""
					(reference "C198")
					(unit 1)
				)
			)
		)
	)
	(symbol
		(lib_id "antmicropower:+3V3")
		(at 245.11 147.32 0)
		(unit 1)
		(exclude_from_sim no)
		(in_bom yes)
		(on_board yes)
		(dnp no)
		(property "Reference" "#PWR0275"
			(at 260.35 147.32 0)
			(effects
				(font
					(size 1.27 1.27)
					(thickness 0.15)
				)
				(justify left bottom)
				(hide yes)
			)
		)
		(property "Value" "+3V3"
			(at 245.11 143.51 0)
			(effects
				(font
					(size 1.27 1.27)
					(thickness 0.15)
				)
			)
		)
		(property "Footprint" ""
			(at 260.35 154.94 0)
			(effects
				(font
					(size 1.27 1.27)
					(thickness 0.15)
				)
				(justify left bottom)
				(hide yes)
			)
		)
		(property "Datasheet" ""
			(at 260.35 157.48 0)
			(effects
				(font
					(size 1.27 1.27)
					(thickness 0.15)
				)
				(justify left bottom)
				(hide yes)
			)
		)
		(property "Description" ""
			(at 245.11 147.32 0)
			(effects
				(font
					(size 1.27 1.27)
				)
				(hide yes)
			)
		)
		(property "Author" "Antmicro"
			(at 260.35 149.86 0)
			(effects
				(font
					(size 1.27 1.27)
					(thickness 0.15)
				)
				(justify left bottom)
				(hide yes)
			)
		)
		(property "License" "Apache-2.0"
			(at 260.35 152.4 0)
			(effects
				(font
					(size 1.27 1.27)
					(thickness 0.15)
				)
				(justify left bottom)
				(hide yes)
			)
		)
		(pin "1"
		)
		(instances
			(project "OCuLink to 10GbE adapter"
				(path ""
					(reference "#PWR0275")
					(unit 1)
				)
			)
		)
	)
	(symbol
		(lib_id "antmicroResistors0402:R_10R_0402")
		(at 151.13 162.56 0)
		(unit 1)
		(exclude_from_sim no)
		(in_bom yes)
		(on_board yes)
		(dnp no)
		(property "Reference" "R48"
			(at 151.13 161.29 0)
			(effects
				(font
					(size 1.27 1.27)
					(thickness 0.15)
				)
				(justify right)
			)
		)
		(property "Value" "R_10R_0402"
			(at 171.45 175.26 0)
			(effects
				(font
					(size 1.27 1.27)
					(thickness 0.15)
				)
				(justify left bottom)
				(hide yes)
			)
		)
		(property "Footprint" "antmicro-footprints:R_0402_1005Metric"
			(at 171.45 177.8 0)
			(effects
				(font
					(size 1.27 1.27)
					(thickness 0.15)
				)
				(justify left bottom)
				(hide yes)
			)
		)
		(property "Datasheet" "https://www.bourns.com/docs/product-datasheets/cr.pdf"
			(at 171.45 180.34 0)
			(effects
				(font
					(size 1.27 1.27)
					(thickness 0.15)
				)
				(justify left bottom)
				(hide yes)
			)
		)
		(property "Description" "SMD Chip Resistor, 10 ohm, ± 1%, 62.5 mW, 0402 [1005 Metric], Thick Film, General Purpose"
			(at 151.13 162.56 0)
			(effects
				(font
					(size 1.27 1.27)
				)
				(hide yes)
			)
		)
		(property "MPN" "CR0402-FX-10R0GLF"
			(at 171.45 182.88 0)
			(effects
				(font
					(size 1.27 1.27)
					(thickness 0.15)
				)
				(justify left bottom)
				(hide yes)
			)
		)
		(property "Manufacturer" "Bourns"
			(at 171.45 185.42 0)
			(effects
				(font
					(size 1.27 1.27)
					(thickness 0.15)
				)
				(justify left bottom)
				(hide yes)
			)
		)
		(property "License" "Apache-2.0"
			(at 171.45 187.96 0)
			(effects
				(font
					(size 1.27 1.27)
					(thickness 0.15)
				)
				(justify left bottom)
				(hide yes)
			)
		)
		(property "Author" "Antmicro"
			(at 171.45 190.5 0)
			(effects
				(font
					(size 1.27 1.27)
					(thickness 0.15)
				)
				(justify left bottom)
				(hide yes)
			)
		)
		(property "Val" "10R"
			(at 156.21 161.29 0)
			(effects
				(font
					(size 1.27 1.27)
					(thickness 0.15)
				)
				(justify left)
			)
		)
		(property "Tolerance" "1%"
			(at 171.45 172.72 0)
			(effects
				(font
					(size 1.27 1.27)
				)
				(justify left bottom)
				(hide yes)
			)
		)
		(pin "1"
		)
		(pin "2"
		)
		(instances
			(project "OCuLink to 10GbE adapter"
				(path ""
					(reference "R48")
					(unit 1)
				)
			)
		)
	)
	(symbol
		(lib_id "antmicroResistors0402:R_1k_0402")
		(at 148.59 172.72 90)
		(unit 1)
		(exclude_from_sim no)
		(in_bom yes)
		(on_board yes)
		(dnp no)
		(property "Reference" "R113"
			(at 150.114 168.91 90)
			(effects
				(font
					(size 1.27 1.27)
					(thickness 0.15)
				)
				(justify right)
			)
		)
		(property "Value" "R_1k_0402"
			(at 161.29 152.4 0)
			(effects
				(font
					(size 1.27 1.27)
					(thickness 0.15)
				)
				(justify left bottom)
				(hide yes)
			)
		)
		(property "Footprint" "antmicro-footprints:R_0402_1005Metric"
			(at 163.83 152.4 0)
			(effects
				(font
					(size 1.27 1.27)
					(thickness 0.15)
				)
				(justify left bottom)
				(hide yes)
			)
		)
		(property "Datasheet" "https://www.bourns.com/docs/product-datasheets/cr.pdf"
			(at 166.37 152.4 0)
			(effects
				(font
					(size 1.27 1.27)
					(thickness 0.15)
				)
				(justify left bottom)
				(hide yes)
			)
		)
		(property "Description" "SMD Chip Resistor, 1 kohm, ± 1%, 63 mW, 0402 [1005 Metric], Thick Film, General Purpose"
			(at 148.59 172.72 0)
			(effects
				(font
					(size 1.27 1.27)
				)
				(hide yes)
			)
		)
		(property "MPN" "CR0402-FX-1001GLF"
			(at 168.91 152.4 0)
			(effects
				(font
					(size 1.27 1.27)
					(thickness 0.15)
				)
				(justify left bottom)
				(hide yes)
			)
		)
		(property "Manufacturer" "Bourns"
			(at 171.45 152.4 0)
			(effects
				(font
					(size 1.27 1.27)
					(thickness 0.15)
				)
				(justify left bottom)
				(hide yes)
			)
		)
		(property "License" "Apache-2.0"
			(at 173.99 152.4 0)
			(effects
				(font
					(size 1.27 1.27)
					(thickness 0.15)
				)
				(justify left bottom)
				(hide yes)
			)
		)
		(property "Author" "Antmicro"
			(at 176.53 152.4 0)
			(effects
				(font
					(size 1.27 1.27)
					(thickness 0.15)
				)
				(justify left bottom)
				(hide yes)
			)
		)
		(property "Val" "1k"
			(at 150.114 171.45 90)
			(effects
				(font
					(size 1.27 1.27)
					(thickness 0.15)
				)
				(justify right)
			)
		)
		(property "Tolerance" "1%"
			(at 158.75 152.4 0)
			(effects
				(font
					(size 1.27 1.27)
				)
				(justify left bottom)
				(hide yes)
			)
		)
		(pin "1"
		)
		(pin "2"
		)
		(instances
			(project "OCuLink to 10GbE adapter"
				(path ""
					(reference "R113")
					(unit 1)
				)
			)
		)
	)
	(symbol
		(lib_id "antmicropower:PWR_FLAG")
		(at 57.15 93.98 0)
		(unit 1)
		(exclude_from_sim no)
		(in_bom yes)
		(on_board yes)
		(dnp no)
		(property "Reference" "#FLG020"
			(at 57.15 92.075 0)
			(effects
				(font
					(size 1.27 1.27)
				)
				(hide yes)
			)
		)
		(property "Value" "PWR_FLAG"
			(at 57.15 90.17 0)
			(effects
				(font
					(size 1.27 1.27)
				)
			)
		)
		(property "Footprint" ""
			(at 57.15 93.98 0)
			(effects
				(font
					(size 1.27 1.27)
				)
				(hide yes)
			)
		)
		(property "Datasheet" ""
			(at 57.15 93.98 0)
			(effects
				(font
					(size 1.27 1.27)
				)
				(hide yes)
			)
		)
		(property "Description" ""
			(at 57.15 93.98 0)
			(effects
				(font
					(size 1.27 1.27)
				)
				(hide yes)
			)
		)
		(pin "1"
		)
		(instances
			(project "OCuLink to 10GbE adapter"
				(path ""
					(reference "#FLG020")
					(unit 1)
				)
			)
		)
	)
	(symbol
		(lib_id "antmicropower:GND")
		(at 130.81 81.28 0)
		(unit 1)
		(exclude_from_sim no)
		(in_bom yes)
		(on_board yes)
		(dnp no)
		(property "Reference" "#PWR0260"
			(at 139.7 83.82 0)
			(effects
				(font
					(size 1.27 1.27)
					(thickness 0.15)
				)
				(justify left bottom)
				(hide yes)
			)
		)
		(property "Value" "GND"
			(at 130.81 85.09 0)
			(effects
				(font
					(size 1.27 1.27)
					(thickness 0.15)
				)
			)
		)
		(property "Footprint" ""
			(at 139.7 88.9 0)
			(effects
				(font
					(size 1.27 1.27)
					(thickness 0.15)
				)
				(justify left bottom)
				(hide yes)
			)
		)
		(property "Datasheet" ""
			(at 139.7 93.98 0)
			(effects
				(font
					(size 1.27 1.27)
					(thickness 0.15)
				)
				(justify left bottom)
				(hide yes)
			)
		)
		(property "Description" ""
			(at 130.81 81.28 0)
			(effects
				(font
					(size 1.27 1.27)
				)
				(hide yes)
			)
		)
		(property "Author" "Antmicro"
			(at 139.7 88.9 0)
			(effects
				(font
					(size 1.27 1.27)
					(thickness 0.15)
				)
				(justify left bottom)
				(hide yes)
			)
		)
		(property "License" "Apache-2.0"
			(at 139.7 91.44 0)
			(effects
				(font
					(size 1.27 1.27)
					(thickness 0.15)
				)
				(justify left bottom)
				(hide yes)
			)
		)
		(pin "1"
		)
		(instances
			(project "OCuLink to 10GbE adapter"
				(path ""
					(reference "#PWR0260")
					(unit 1)
				)
			)
		)
	)
	(symbol
		(lib_id "antmicroResistors0402:R_10k_0402")
		(at 265.43 96.52 90)
		(unit 1)
		(exclude_from_sim no)
		(in_bom yes)
		(on_board yes)
		(dnp no)
		(property "Reference" "R93"
			(at 266.954 92.71 90)
			(effects
				(font
					(size 1.27 1.27)
					(thickness 0.15)
				)
				(justify right)
			)
		)
		(property "Value" "R_10k_0402"
			(at 278.13 76.2 0)
			(effects
				(font
					(size 1.27 1.27)
					(thickness 0.15)
				)
				(justify left bottom)
				(hide yes)
			)
		)
		(property "Footprint" "antmicro-footprints:R_0402_1005Metric"
			(at 280.67 76.2 0)
			(effects
				(font
					(size 1.27 1.27)
					(thickness 0.15)
				)
				(justify left bottom)
				(hide yes)
			)
		)
		(property "Datasheet" "https://www.bourns.com/docs/product-datasheets/cr.pdf"
			(at 283.21 76.2 0)
			(effects
				(font
					(size 1.27 1.27)
					(thickness 0.15)
				)
				(justify left bottom)
				(hide yes)
			)
		)
		(property "Description" "SMD Chip Resistor, 10 kohm, ± 1%, 62.5 mW, 0402 [1005 Metric], Thick Film, General Purpose"
			(at 265.43 96.52 0)
			(effects
				(font
					(size 1.27 1.27)
				)
				(hide yes)
			)
		)
		(property "MPN" "CR0402-FX-1002GLF"
			(at 285.75 76.2 0)
			(effects
				(font
					(size 1.27 1.27)
					(thickness 0.15)
				)
				(justify left bottom)
				(hide yes)
			)
		)
		(property "Manufacturer" "Bourns"
			(at 288.29 76.2 0)
			(effects
				(font
					(size 1.27 1.27)
					(thickness 0.15)
				)
				(justify left bottom)
				(hide yes)
			)
		)
		(property "License" "Apache-2.0"
			(at 290.83 76.2 0)
			(effects
				(font
					(size 1.27 1.27)
					(thickness 0.15)
				)
				(justify left bottom)
				(hide yes)
			)
		)
		(property "Author" "Antmicro"
			(at 293.37 76.2 0)
			(effects
				(font
					(size 1.27 1.27)
					(thickness 0.15)
				)
				(justify left bottom)
				(hide yes)
			)
		)
		(property "Val" "10k"
			(at 266.954 95.25 90)
			(effects
				(font
					(size 1.27 1.27)
					(thickness 0.15)
				)
				(justify right)
			)
		)
		(property "Tolerance" "1%"
			(at 275.59 76.2 0)
			(effects
				(font
					(size 1.27 1.27)
				)
				(justify left bottom)
				(hide yes)
			)
		)
		(pin "2"
		)
		(pin "1"
		)
		(instances
			(project ""
				(path ""
					(reference "R93")
					(unit 1)
				)
			)
		)
	)
	(symbol
		(lib_id "antmicroResistors0402:R_2k_0402")
		(at 53.34 220.98 270)
		(mirror x)
		(unit 1)
		(exclude_from_sim no)
		(in_bom yes)
		(on_board yes)
		(dnp no)
		(property "Reference" "R171"
			(at 52.07 217.17 90)
			(effects
				(font
					(size 1.27 1.27)
					(thickness 0.15)
				)
				(justify right)
			)
		)
		(property "Value" "R_2k_0402"
			(at 40.64 200.66 0)
			(effects
				(font
					(size 1.27 1.27)
					(thickness 0.15)
				)
				(justify left bottom)
				(hide yes)
			)
		)
		(property "Footprint" "antmicro-footprints:R_0402_1005Metric"
			(at 38.1 200.66 0)
			(effects
				(font
					(size 1.27 1.27)
					(thickness 0.15)
				)
				(justify left bottom)
				(hide yes)
			)
		)
		(property "Datasheet" "https://www.bourns.com/docs/product-datasheets/cr.pdf"
			(at 35.56 200.66 0)
			(effects
				(font
					(size 1.27 1.27)
					(thickness 0.15)
				)
				(justify left bottom)
				(hide yes)
			)
		)
		(property "Description" "SMD Chip Resistor, 2 kohm, ± 1%, 62.5 mW, 0402 [1005 Metric], Thick Film, General Purpose"
			(at 22.86 200.66 0)
			(effects
				(font
					(size 1.27 1.27)
				)
				(justify left bottom)
				(hide yes)
			)
		)
		(property "MPN" "CR0402-FX-2001GLF"
			(at 33.02 200.66 0)
			(effects
				(font
					(size 1.27 1.27)
					(thickness 0.15)
				)
				(justify left bottom)
				(hide yes)
			)
		)
		(property "Manufacturer" "Bourns"
			(at 30.48 200.66 0)
			(effects
				(font
					(size 1.27 1.27)
					(thickness 0.15)
				)
				(justify left bottom)
				(hide yes)
			)
		)
		(property "License" "Apache-2.0"
			(at 27.94 200.66 0)
			(effects
				(font
					(size 1.27 1.27)
					(thickness 0.15)
				)
				(justify left bottom)
				(hide yes)
			)
		)
		(property "Author" "Antmicro"
			(at 25.4 200.66 0)
			(effects
				(font
					(size 1.27 1.27)
					(thickness 0.15)
				)
				(justify left bottom)
				(hide yes)
			)
		)
		(property "Val" "2k"
			(at 52.07 219.71 90)
			(effects
				(font
					(size 1.27 1.27)
					(thickness 0.15)
				)
				(justify right)
			)
		)
		(property "Tolerance" "1%"
			(at 43.18 200.66 0)
			(effects
				(font
					(size 1.27 1.27)
				)
				(justify left bottom)
				(hide yes)
			)
		)
		(pin "2"
		)
		(pin "1"
		)
		(instances
			(project "OCuLink to 10GbE adapter"
				(path ""
					(reference "R171")
					(unit 1)
				)
			)
		)
	)
	(symbol
		(lib_id "antmicropower:GND")
		(at 242.57 246.38 0)
		(unit 1)
		(exclude_from_sim no)
		(in_bom yes)
		(on_board yes)
		(dnp no)
		(property "Reference" "#PWR0284"
			(at 251.46 248.92 0)
			(effects
				(font
					(size 1.27 1.27)
					(thickness 0.15)
				)
				(justify left bottom)
				(hide yes)
			)
		)
		(property "Value" "GND"
			(at 242.57 250.19 0)
			(effects
				(font
					(size 1.27 1.27)
					(thickness 0.15)
				)
			)
		)
		(property "Footprint" ""
			(at 251.46 254 0)
			(effects
				(font
					(size 1.27 1.27)
					(thickness 0.15)
				)
				(justify left bottom)
				(hide yes)
			)
		)
		(property "Datasheet" ""
			(at 251.46 259.08 0)
			(effects
				(font
					(size 1.27 1.27)
					(thickness 0.15)
				)
				(justify left bottom)
				(hide yes)
			)
		)
		(property "Description" ""
			(at 242.57 246.38 0)
			(effects
				(font
					(size 1.27 1.27)
				)
				(hide yes)
			)
		)
		(property "Author" "Antmicro"
			(at 251.46 254 0)
			(effects
				(font
					(size 1.27 1.27)
					(thickness 0.15)
				)
				(justify left bottom)
				(hide yes)
			)
		)
		(property "License" "Apache-2.0"
			(at 251.46 256.54 0)
			(effects
				(font
					(size 1.27 1.27)
					(thickness 0.15)
				)
				(justify left bottom)
				(hide yes)
			)
		)
		(pin "1"
		)
		(instances
			(project "OCuLink to 10GbE adapter"
				(path ""
					(reference "#PWR0284")
					(unit 1)
				)
			)
		)
	)
	(symbol
		(lib_id "antmicropower:GND")
		(at 62.23 181.61 0)
		(mirror y)
		(unit 1)
		(exclude_from_sim no)
		(in_bom yes)
		(on_board yes)
		(dnp no)
		(property "Reference" "#PWR0110"
			(at 53.34 184.15 0)
			(effects
				(font
					(size 1.27 1.27)
					(thickness 0.15)
				)
				(justify left bottom)
				(hide yes)
			)
		)
		(property "Value" "GND"
			(at 62.23 185.42 0)
			(effects
				(font
					(size 1.27 1.27)
					(thickness 0.15)
				)
			)
		)
		(property "Footprint" ""
			(at 53.34 189.23 0)
			(effects
				(font
					(size 1.27 1.27)
					(thickness 0.15)
				)
				(justify left bottom)
				(hide yes)
			)
		)
		(property "Datasheet" ""
			(at 53.34 194.31 0)
			(effects
				(font
					(size 1.27 1.27)
					(thickness 0.15)
				)
				(justify left bottom)
				(hide yes)
			)
		)
		(property "Description" ""
			(at 62.23 181.61 0)
			(effects
				(font
					(size 1.27 1.27)
				)
				(hide yes)
			)
		)
		(property "Author" "Antmicro"
			(at 53.34 189.23 0)
			(effects
				(font
					(size 1.27 1.27)
					(thickness 0.15)
				)
				(justify left bottom)
				(hide yes)
			)
		)
		(property "License" "Apache-2.0"
			(at 53.34 191.77 0)
			(effects
				(font
					(size 1.27 1.27)
					(thickness 0.15)
				)
				(justify left bottom)
				(hide yes)
			)
		)
		(pin "1"
		)
		(instances
			(project "OCuLink to 10GbE adapter"
				(path ""
					(reference "#PWR0110")
					(unit 1)
				)
			)
		)
	)
	(symbol
		(lib_id "antmicropower:GND")
		(at 146.05 132.08 0)
		(unit 1)
		(exclude_from_sim no)
		(in_bom yes)
		(on_board yes)
		(dnp no)
		(property "Reference" "#PWR0272"
			(at 154.94 134.62 0)
			(effects
				(font
					(size 1.27 1.27)
					(thickness 0.15)
				)
				(justify left bottom)
				(hide yes)
			)
		)
		(property "Value" "GND"
			(at 146.05 135.89 0)
			(effects
				(font
					(size 1.27 1.27)
					(thickness 0.15)
				)
			)
		)
		(property "Footprint" ""
			(at 154.94 139.7 0)
			(effects
				(font
					(size 1.27 1.27)
					(thickness 0.15)
				)
				(justify left bottom)
				(hide yes)
			)
		)
		(property "Datasheet" ""
			(at 154.94 144.78 0)
			(effects
				(font
					(size 1.27 1.27)
					(thickness 0.15)
				)
				(justify left bottom)
				(hide yes)
			)
		)
		(property "Description" ""
			(at 146.05 132.08 0)
			(effects
				(font
					(size 1.27 1.27)
				)
				(hide yes)
			)
		)
		(property "Author" "Antmicro"
			(at 154.94 139.7 0)
			(effects
				(font
					(size 1.27 1.27)
					(thickness 0.15)
				)
				(justify left bottom)
				(hide yes)
			)
		)
		(property "License" "Apache-2.0"
			(at 154.94 142.24 0)
			(effects
				(font
					(size 1.27 1.27)
					(thickness 0.15)
				)
				(justify left bottom)
				(hide yes)
			)
		)
		(pin "1"
		)
		(instances
			(project "OCuLink to 10GbE adapter"
				(path ""
					(reference "#PWR0272")
					(unit 1)
				)
			)
		)
	)
	(symbol
		(lib_id "antmicroResistors0402:R_100R_0402")
		(at 146.05 129.54 90)
		(unit 1)
		(exclude_from_sim no)
		(in_bom no)
		(on_board yes)
		(dnp yes)
		(property "Reference" "R108"
			(at 147.574 125.73 90)
			(effects
				(font
					(size 1.27 1.27)
					(thickness 0.15)
				)
				(justify right)
			)
		)
		(property "Value" "R_100R_0402"
			(at 158.75 109.22 0)
			(effects
				(font
					(size 1.27 1.27)
					(thickness 0.15)
				)
				(justify left bottom)
				(hide yes)
			)
		)
		(property "Footprint" "antmicro-footprints:R_0402_1005Metric"
			(at 161.29 109.22 0)
			(effects
				(font
					(size 1.27 1.27)
					(thickness 0.15)
				)
				(justify left bottom)
				(hide yes)
			)
		)
		(property "Datasheet" "https://www.bourns.com/docs/product-datasheets/cr.pdf"
			(at 163.83 109.22 0)
			(effects
				(font
					(size 1.27 1.27)
					(thickness 0.15)
				)
				(justify left bottom)
				(hide yes)
			)
		)
		(property "Description" "SMD Chip Resistor, 100 ohm, ± 1%, 62.5 mW, 0402 [1005 Metric], Thick Film, General Purpose"
			(at 146.05 129.54 0)
			(effects
				(font
					(size 1.27 1.27)
				)
				(hide yes)
			)
		)
		(property "MPN" "CR0402-FX-1000GLF"
			(at 166.37 109.22 0)
			(effects
				(font
					(size 1.27 1.27)
					(thickness 0.15)
				)
				(justify left bottom)
				(hide yes)
			)
		)
		(property "Manufacturer" "Bourns"
			(at 168.91 109.22 0)
			(effects
				(font
					(size 1.27 1.27)
					(thickness 0.15)
				)
				(justify left bottom)
				(hide yes)
			)
		)
		(property "License" "Apache-2.0"
			(at 171.45 109.22 0)
			(effects
				(font
					(size 1.27 1.27)
					(thickness 0.15)
				)
				(justify left bottom)
				(hide yes)
			)
		)
		(property "Author" "Antmicro"
			(at 173.99 109.22 0)
			(effects
				(font
					(size 1.27 1.27)
					(thickness 0.15)
				)
				(justify left bottom)
				(hide yes)
			)
		)
		(property "Val" "100R"
			(at 147.574 128.27 90)
			(effects
				(font
					(size 1.27 1.27)
					(thickness 0.15)
				)
				(justify right)
			)
		)
		(property "Tolerance" "1%"
			(at 156.21 109.22 0)
			(effects
				(font
					(size 1.27 1.27)
				)
				(justify left bottom)
				(hide yes)
			)
		)
		(pin "2"
		)
		(pin "1"
		)
		(instances
			(project "OCuLink to 10GbE adapter"
				(path ""
					(reference "R108")
					(unit 1)
				)
			)
		)
	)
	(symbol
		(lib_id "antmicropower:GND")
		(at 128.27 175.26 0)
		(unit 1)
		(exclude_from_sim no)
		(in_bom yes)
		(on_board yes)
		(dnp no)
		(property "Reference" "#PWR096"
			(at 137.16 177.8 0)
			(effects
				(font
					(size 1.27 1.27)
					(thickness 0.15)
				)
				(justify left bottom)
				(hide yes)
			)
		)
		(property "Value" "GND"
			(at 128.27 179.07 0)
			(effects
				(font
					(size 1.27 1.27)
					(thickness 0.15)
				)
			)
		)
		(property "Footprint" ""
			(at 137.16 182.88 0)
			(effects
				(font
					(size 1.27 1.27)
					(thickness 0.15)
				)
				(justify left bottom)
				(hide yes)
			)
		)
		(property "Datasheet" ""
			(at 137.16 187.96 0)
			(effects
				(font
					(size 1.27 1.27)
					(thickness 0.15)
				)
				(justify left bottom)
				(hide yes)
			)
		)
		(property "Description" ""
			(at 128.27 175.26 0)
			(effects
				(font
					(size 1.27 1.27)
				)
				(hide yes)
			)
		)
		(property "Author" "Antmicro"
			(at 137.16 182.88 0)
			(effects
				(font
					(size 1.27 1.27)
					(thickness 0.15)
				)
				(justify left bottom)
				(hide yes)
			)
		)
		(property "License" "Apache-2.0"
			(at 137.16 185.42 0)
			(effects
				(font
					(size 1.27 1.27)
					(thickness 0.15)
				)
				(justify left bottom)
				(hide yes)
			)
		)
		(pin "1"
		)
		(instances
			(project "OCuLink to 10GbE adapter"
				(path ""
					(reference "#PWR096")
					(unit 1)
				)
			)
		)
	)
	(symbol
		(lib_id "antmicroResistors0402:R_10R_0402")
		(at 151.13 160.02 0)
		(unit 1)
		(exclude_from_sim no)
		(in_bom yes)
		(on_board yes)
		(dnp no)
		(property "Reference" "R47"
			(at 151.13 158.75 0)
			(effects
				(font
					(size 1.27 1.27)
					(thickness 0.15)
				)
				(justify right)
			)
		)
		(property "Value" "R_10R_0402"
			(at 171.45 172.72 0)
			(effects
				(font
					(size 1.27 1.27)
					(thickness 0.15)
				)
				(justify left bottom)
				(hide yes)
			)
		)
		(property "Footprint" "antmicro-footprints:R_0402_1005Metric"
			(at 171.45 175.26 0)
			(effects
				(font
					(size 1.27 1.27)
					(thickness 0.15)
				)
				(justify left bottom)
				(hide yes)
			)
		)
		(property "Datasheet" "https://www.bourns.com/docs/product-datasheets/cr.pdf"
			(at 171.45 177.8 0)
			(effects
				(font
					(size 1.27 1.27)
					(thickness 0.15)
				)
				(justify left bottom)
				(hide yes)
			)
		)
		(property "Description" "SMD Chip Resistor, 10 ohm, ± 1%, 62.5 mW, 0402 [1005 Metric], Thick Film, General Purpose"
			(at 151.13 160.02 0)
			(effects
				(font
					(size 1.27 1.27)
				)
				(hide yes)
			)
		)
		(property "MPN" "CR0402-FX-10R0GLF"
			(at 171.45 180.34 0)
			(effects
				(font
					(size 1.27 1.27)
					(thickness 0.15)
				)
				(justify left bottom)
				(hide yes)
			)
		)
		(property "Manufacturer" "Bourns"
			(at 171.45 182.88 0)
			(effects
				(font
					(size 1.27 1.27)
					(thickness 0.15)
				)
				(justify left bottom)
				(hide yes)
			)
		)
		(property "License" "Apache-2.0"
			(at 171.45 185.42 0)
			(effects
				(font
					(size 1.27 1.27)
					(thickness 0.15)
				)
				(justify left bottom)
				(hide yes)
			)
		)
		(property "Author" "Antmicro"
			(at 171.45 187.96 0)
			(effects
				(font
					(size 1.27 1.27)
					(thickness 0.15)
				)
				(justify left bottom)
				(hide yes)
			)
		)
		(property "Val" "10R"
			(at 156.21 158.75 0)
			(effects
				(font
					(size 1.27 1.27)
					(thickness 0.15)
				)
				(justify left)
			)
		)
		(property "Tolerance" "1%"
			(at 171.45 170.18 0)
			(effects
				(font
					(size 1.27 1.27)
				)
				(justify left bottom)
				(hide yes)
			)
		)
		(pin "1"
		)
		(pin "2"
		)
		(instances
			(project "OCuLink to 10GbE adapter"
				(path ""
					(reference "R47")
					(unit 1)
				)
			)
		)
	)
	(symbol
		(lib_id "antmicroResistors0402:R_100R_0402")
		(at 154.94 129.54 90)
		(unit 1)
		(exclude_from_sim no)
		(in_bom no)
		(on_board yes)
		(dnp yes)
		(property "Reference" "R109"
			(at 156.464 125.73 90)
			(effects
				(font
					(size 1.27 1.27)
					(thickness 0.15)
				)
				(justify right)
			)
		)
		(property "Value" "R_100R_0402"
			(at 167.64 109.22 0)
			(effects
				(font
					(size 1.27 1.27)
					(thickness 0.15)
				)
				(justify left bottom)
				(hide yes)
			)
		)
		(property "Footprint" "antmicro-footprints:R_0402_1005Metric"
			(at 170.18 109.22 0)
			(effects
				(font
					(size 1.27 1.27)
					(thickness 0.15)
				)
				(justify left bottom)
				(hide yes)
			)
		)
		(property "Datasheet" "https://www.bourns.com/docs/product-datasheets/cr.pdf"
			(at 172.72 109.22 0)
			(effects
				(font
					(size 1.27 1.27)
					(thickness 0.15)
				)
				(justify left bottom)
				(hide yes)
			)
		)
		(property "Description" "SMD Chip Resistor, 100 ohm, ± 1%, 62.5 mW, 0402 [1005 Metric], Thick Film, General Purpose"
			(at 154.94 129.54 0)
			(effects
				(font
					(size 1.27 1.27)
				)
				(hide yes)
			)
		)
		(property "MPN" "CR0402-FX-1000GLF"
			(at 175.26 109.22 0)
			(effects
				(font
					(size 1.27 1.27)
					(thickness 0.15)
				)
				(justify left bottom)
				(hide yes)
			)
		)
		(property "Manufacturer" "Bourns"
			(at 177.8 109.22 0)
			(effects
				(font
					(size 1.27 1.27)
					(thickness 0.15)
				)
				(justify left bottom)
				(hide yes)
			)
		)
		(property "License" "Apache-2.0"
			(at 180.34 109.22 0)
			(effects
				(font
					(size 1.27 1.27)
					(thickness 0.15)
				)
				(justify left bottom)
				(hide yes)
			)
		)
		(property "Author" "Antmicro"
			(at 182.88 109.22 0)
			(effects
				(font
					(size 1.27 1.27)
					(thickness 0.15)
				)
				(justify left bottom)
				(hide yes)
			)
		)
		(property "Val" "100R"
			(at 156.464 128.27 90)
			(effects
				(font
					(size 1.27 1.27)
					(thickness 0.15)
				)
				(justify right)
			)
		)
		(property "Tolerance" "1%"
			(at 165.1 109.22 0)
			(effects
				(font
					(size 1.27 1.27)
				)
				(justify left bottom)
				(hide yes)
			)
		)
		(pin "2"
		)
		(pin "1"
		)
		(instances
			(project ""
				(path ""
					(reference "R109")
					(unit 1)
				)
			)
		)
	)
	(symbol
		(lib_id "antmicropower:+3V3")
		(at 33.02 93.98 0)
		(unit 1)
		(exclude_from_sim no)
		(in_bom yes)
		(on_board yes)
		(dnp no)
		(property "Reference" "#PWR0265"
			(at 48.26 93.98 0)
			(effects
				(font
					(size 1.27 1.27)
					(thickness 0.15)
				)
				(justify left bottom)
				(hide yes)
			)
		)
		(property "Value" "+3V3"
			(at 33.02 90.17 0)
			(effects
				(font
					(size 1.27 1.27)
					(thickness 0.15)
				)
			)
		)
		(property "Footprint" ""
			(at 48.26 101.6 0)
			(effects
				(font
					(size 1.27 1.27)
					(thickness 0.15)
				)
				(justify left bottom)
				(hide yes)
			)
		)
		(property "Datasheet" ""
			(at 48.26 104.14 0)
			(effects
				(font
					(size 1.27 1.27)
					(thickness 0.15)
				)
				(justify left bottom)
				(hide yes)
			)
		)
		(property "Description" ""
			(at 33.02 93.98 0)
			(effects
				(font
					(size 1.27 1.27)
				)
				(hide yes)
			)
		)
		(property "Author" "Antmicro"
			(at 48.26 96.52 0)
			(effects
				(font
					(size 1.27 1.27)
					(thickness 0.15)
				)
				(justify left bottom)
				(hide yes)
			)
		)
		(property "License" "Apache-2.0"
			(at 48.26 99.06 0)
			(effects
				(font
					(size 1.27 1.27)
					(thickness 0.15)
				)
				(justify left bottom)
				(hide yes)
			)
		)
		(pin "1"
		)
		(instances
			(project "OCuLink to 10GbE adapter"
				(path ""
					(reference "#PWR0265")
					(unit 1)
				)
			)
		)
	)
	(symbol
		(lib_id "antmicroTestPoints:TP_0.75mm_SMD")
		(at 170.18 226.06 180)
		(unit 1)
		(exclude_from_sim no)
		(in_bom no)
		(on_board yes)
		(dnp no)
		(property "Reference" "TP10"
			(at 165.862 226.06 0)
			(effects
				(font
					(size 1.27 1.27)
					(thickness 0.15)
				)
				(justify left)
			)
		)
		(property "Value" "TP_0.75mm_SMD"
			(at 160.02 222.25 0)
			(effects
				(font
					(size 1.27 1.27)
					(thickness 0.15)
				)
				(justify left bottom)
				(hide yes)
			)
		)
		(property "Footprint" "antmicro-footprints:TP_SMD_0.75mm"
			(at 160.02 219.71 0)
			(effects
				(font
					(size 1.27 1.27)
					(thickness 0.15)
				)
				(justify left bottom)
				(hide yes)
			)
		)
		(property "Datasheet" ""
			(at 152.4 213.36 0)
			(effects
				(font
					(size 1.27 1.27)
					(thickness 0.15)
				)
				(justify left bottom)
				(hide yes)
			)
		)
		(property "Description" "SMT test point"
			(at 170.18 226.06 0)
			(effects
				(font
					(size 1.27 1.27)
				)
				(hide yes)
			)
		)
		(property "MPN" ""
			(at 159.385 214.63 0)
			(effects
				(font
					(size 1.27 1.27)
					(thickness 0.15)
				)
				(justify left bottom)
				(hide yes)
			)
		)
		(property "Manufacturer" ""
			(at 159.385 219.71 0)
			(effects
				(font
					(size 1.27 1.27)
					(thickness 0.15)
				)
				(justify left bottom)
				(hide yes)
			)
		)
		(property "Author" "Antmicro"
			(at 160.02 217.17 0)
			(effects
				(font
					(size 1.27 1.27)
					(thickness 0.15)
				)
				(justify left bottom)
				(hide yes)
			)
		)
		(property "License" "Apache-2.0"
			(at 160.02 214.63 0)
			(effects
				(font
					(size 1.27 1.27)
					(thickness 0.15)
				)
				(justify left bottom)
				(hide yes)
			)
		)
		(pin "1"
		)
		(instances
			(project ""
				(path ""
					(reference "TP10")
					(unit 1)
				)
			)
		)
	)
	(symbol
		(lib_id "antmicropower:GND")
		(at 96.52 223.52 0)
		(mirror y)
		(unit 1)
		(exclude_from_sim no)
		(in_bom yes)
		(on_board yes)
		(dnp no)
		(property "Reference" "#PWR0101"
			(at 87.63 226.06 0)
			(effects
				(font
					(size 1.27 1.27)
					(thickness 0.15)
				)
				(justify left bottom)
				(hide yes)
			)
		)
		(property "Value" "GND"
			(at 96.52 227.33 0)
			(effects
				(font
					(size 1.27 1.27)
					(thickness 0.15)
				)
			)
		)
		(property "Footprint" ""
			(at 87.63 231.14 0)
			(effects
				(font
					(size 1.27 1.27)
					(thickness 0.15)
				)
				(justify left bottom)
				(hide yes)
			)
		)
		(property "Datasheet" ""
			(at 87.63 236.22 0)
			(effects
				(font
					(size 1.27 1.27)
					(thickness 0.15)
				)
				(justify left bottom)
				(hide yes)
			)
		)
		(property "Description" ""
			(at 96.52 223.52 0)
			(effects
				(font
					(size 1.27 1.27)
				)
				(hide yes)
			)
		)
		(property "Author" "Antmicro"
			(at 87.63 231.14 0)
			(effects
				(font
					(size 1.27 1.27)
					(thickness 0.15)
				)
				(justify left bottom)
				(hide yes)
			)
		)
		(property "License" "Apache-2.0"
			(at 87.63 233.68 0)
			(effects
				(font
					(size 1.27 1.27)
					(thickness 0.15)
				)
				(justify left bottom)
				(hide yes)
			)
		)
		(pin "1"
		)
		(instances
			(project "OCuLink to 10GbE adapter"
				(path ""
					(reference "#PWR0101")
					(unit 1)
				)
			)
		)
	)
	(symbol
		(lib_id "antmicropower:GND")
		(at 123.19 246.38 0)
		(unit 1)
		(exclude_from_sim no)
		(in_bom yes)
		(on_board yes)
		(dnp no)
		(property "Reference" "#PWR0279"
			(at 132.08 248.92 0)
			(effects
				(font
					(size 1.27 1.27)
					(thickness 0.15)
				)
				(justify left bottom)
				(hide yes)
			)
		)
		(property "Value" "GND"
			(at 123.19 250.19 0)
			(effects
				(font
					(size 1.27 1.27)
					(thickness 0.15)
				)
			)
		)
		(property "Footprint" ""
			(at 132.08 254 0)
			(effects
				(font
					(size 1.27 1.27)
					(thickness 0.15)
				)
				(justify left bottom)
				(hide yes)
			)
		)
		(property "Datasheet" ""
			(at 132.08 259.08 0)
			(effects
				(font
					(size 1.27 1.27)
					(thickness 0.15)
				)
				(justify left bottom)
				(hide yes)
			)
		)
		(property "Description" ""
			(at 123.19 246.38 0)
			(effects
				(font
					(size 1.27 1.27)
				)
				(hide yes)
			)
		)
		(property "Author" "Antmicro"
			(at 132.08 254 0)
			(effects
				(font
					(size 1.27 1.27)
					(thickness 0.15)
				)
				(justify left bottom)
				(hide yes)
			)
		)
		(property "License" "Apache-2.0"
			(at 132.08 256.54 0)
			(effects
				(font
					(size 1.27 1.27)
					(thickness 0.15)
				)
				(justify left bottom)
				(hide yes)
			)
		)
		(pin "1"
		)
		(instances
			(project "OCuLink to 10GbE adapter"
				(path ""
					(reference "#PWR0279")
					(unit 1)
				)
			)
		)
	)
	(symbol
		(lib_id "antmicroResistors0402:R_10k_0402")
		(at 256.54 96.52 90)
		(unit 1)
		(exclude_from_sim no)
		(in_bom yes)
		(on_board yes)
		(dnp no)
		(property "Reference" "R92"
			(at 258.064 92.71 90)
			(effects
				(font
					(size 1.27 1.27)
					(thickness 0.15)
				)
				(justify right)
			)
		)
		(property "Value" "R_10k_0402"
			(at 269.24 76.2 0)
			(effects
				(font
					(size 1.27 1.27)
					(thickness 0.15)
				)
				(justify left bottom)
				(hide yes)
			)
		)
		(property "Footprint" "antmicro-footprints:R_0402_1005Metric"
			(at 271.78 76.2 0)
			(effects
				(font
					(size 1.27 1.27)
					(thickness 0.15)
				)
				(justify left bottom)
				(hide yes)
			)
		)
		(property "Datasheet" "https://www.bourns.com/docs/product-datasheets/cr.pdf"
			(at 274.32 76.2 0)
			(effects
				(font
					(size 1.27 1.27)
					(thickness 0.15)
				)
				(justify left bottom)
				(hide yes)
			)
		)
		(property "Description" "SMD Chip Resistor, 10 kohm, ± 1%, 62.5 mW, 0402 [1005 Metric], Thick Film, General Purpose"
			(at 256.54 96.52 0)
			(effects
				(font
					(size 1.27 1.27)
				)
				(hide yes)
			)
		)
		(property "MPN" "CR0402-FX-1002GLF"
			(at 276.86 76.2 0)
			(effects
				(font
					(size 1.27 1.27)
					(thickness 0.15)
				)
				(justify left bottom)
				(hide yes)
			)
		)
		(property "Manufacturer" "Bourns"
			(at 279.4 76.2 0)
			(effects
				(font
					(size 1.27 1.27)
					(thickness 0.15)
				)
				(justify left bottom)
				(hide yes)
			)
		)
		(property "License" "Apache-2.0"
			(at 281.94 76.2 0)
			(effects
				(font
					(size 1.27 1.27)
					(thickness 0.15)
				)
				(justify left bottom)
				(hide yes)
			)
		)
		(property "Author" "Antmicro"
			(at 284.48 76.2 0)
			(effects
				(font
					(size 1.27 1.27)
					(thickness 0.15)
				)
				(justify left bottom)
				(hide yes)
			)
		)
		(property "Val" "10k"
			(at 258.064 95.25 90)
			(effects
				(font
					(size 1.27 1.27)
					(thickness 0.15)
				)
				(justify right)
			)
		)
		(property "Tolerance" "1%"
			(at 266.7 76.2 0)
			(effects
				(font
					(size 1.27 1.27)
				)
				(justify left bottom)
				(hide yes)
			)
		)
		(pin "2"
		)
		(pin "1"
		)
		(instances
			(project "OCuLink to 10GbE adapter"
				(path ""
					(reference "R92")
					(unit 1)
				)
			)
		)
	)
	(symbol
		(lib_id "antmicroResistors0402:R_1k_0402")
		(at 267.97 204.47 90)
		(unit 1)
		(exclude_from_sim no)
		(in_bom yes)
		(on_board yes)
		(dnp no)
		(property "Reference" "R117"
			(at 269.494 200.66 90)
			(effects
				(font
					(size 1.27 1.27)
					(thickness 0.15)
				)
				(justify right)
			)
		)
		(property "Value" "R_1k_0402"
			(at 280.67 184.15 0)
			(effects
				(font
					(size 1.27 1.27)
					(thickness 0.15)
				)
				(justify left bottom)
				(hide yes)
			)
		)
		(property "Footprint" "antmicro-footprints:R_0402_1005Metric"
			(at 283.21 184.15 0)
			(effects
				(font
					(size 1.27 1.27)
					(thickness 0.15)
				)
				(justify left bottom)
				(hide yes)
			)
		)
		(property "Datasheet" "https://www.bourns.com/docs/product-datasheets/cr.pdf"
			(at 285.75 184.15 0)
			(effects
				(font
					(size 1.27 1.27)
					(thickness 0.15)
				)
				(justify left bottom)
				(hide yes)
			)
		)
		(property "Description" "SMD Chip Resistor, 1 kohm, ± 1%, 63 mW, 0402 [1005 Metric], Thick Film, General Purpose"
			(at 267.97 204.47 0)
			(effects
				(font
					(size 1.27 1.27)
				)
				(hide yes)
			)
		)
		(property "MPN" "CR0402-FX-1001GLF"
			(at 288.29 184.15 0)
			(effects
				(font
					(size 1.27 1.27)
					(thickness 0.15)
				)
				(justify left bottom)
				(hide yes)
			)
		)
		(property "Manufacturer" "Bourns"
			(at 290.83 184.15 0)
			(effects
				(font
					(size 1.27 1.27)
					(thickness 0.15)
				)
				(justify left bottom)
				(hide yes)
			)
		)
		(property "License" "Apache-2.0"
			(at 293.37 184.15 0)
			(effects
				(font
					(size 1.27 1.27)
					(thickness 0.15)
				)
				(justify left bottom)
				(hide yes)
			)
		)
		(property "Author" "Antmicro"
			(at 295.91 184.15 0)
			(effects
				(font
					(size 1.27 1.27)
					(thickness 0.15)
				)
				(justify left bottom)
				(hide yes)
			)
		)
		(property "Val" "1k"
			(at 269.494 203.2 90)
			(effects
				(font
					(size 1.27 1.27)
					(thickness 0.15)
				)
				(justify right)
			)
		)
		(property "Tolerance" "1%"
			(at 278.13 184.15 0)
			(effects
				(font
					(size 1.27 1.27)
				)
				(justify left bottom)
				(hide yes)
			)
		)
		(pin "2"
		)
		(pin "1"
		)
		(instances
			(project "OCuLink to 10GbE adapter"
				(path ""
					(reference "R117")
					(unit 1)
				)
			)
		)
	)
	(symbol
		(lib_id "antmicroCapacitors0402:C_5p6_0402")
		(at 128.27 172.72 90)
		(unit 1)
		(exclude_from_sim no)
		(in_bom yes)
		(on_board yes)
		(dnp no)
		(property "Reference" "C72"
			(at 130.302 168.91 90)
			(effects
				(font
					(size 1.27 1.27)
					(thickness 0.15)
				)
				(justify right)
			)
		)
		(property "Value" "C_5p6_0402"
			(at 138.43 152.4 0)
			(effects
				(font
					(size 1.27 1.27)
					(thickness 0.15)
				)
				(justify left bottom)
				(hide yes)
			)
		)
		(property "Footprint" "antmicro-footprints:C_0402_1005Metric"
			(at 140.97 152.4 0)
			(effects
				(font
					(size 1.27 1.27)
					(thickness 0.15)
				)
				(justify left bottom)
				(hide yes)
			)
		)
		(property "Datasheet" "https://www.mouser.com/datasheet/3/76/2/GCM1555C1H5R6BA16_01A.pdf"
			(at 143.51 152.4 0)
			(effects
				(font
					(size 1.27 1.27)
					(thickness 0.15)
				)
				(justify left bottom)
				(hide yes)
			)
		)
		(property "Description" "Multilayer Ceramic Capacitors MLCC - SMD/SMT 5.6 pF 50 VDC 0.1 pF 0402 C0G (NP0) AEC-Q200"
			(at 128.27 172.72 0)
			(effects
				(font
					(size 1.27 1.27)
				)
				(hide yes)
			)
		)
		(property "MPN" "GCM1555C1H5R6BA16D"
			(at 146.05 152.4 0)
			(effects
				(font
					(size 1.27 1.27)
					(thickness 0.15)
				)
				(justify left bottom)
				(hide yes)
			)
		)
		(property "Manufacturer" "Murata"
			(at 148.59 152.4 0)
			(effects
				(font
					(size 1.27 1.27)
					(thickness 0.15)
				)
				(justify left bottom)
				(hide yes)
			)
		)
		(property "License" "Apache-2.0"
			(at 151.13 152.4 0)
			(effects
				(font
					(size 1.27 1.27)
					(thickness 0.15)
				)
				(justify left bottom)
				(hide yes)
			)
		)
		(property "Author" "Antmicro"
			(at 153.67 152.4 0)
			(effects
				(font
					(size 1.27 1.27)
					(thickness 0.15)
				)
				(justify left bottom)
				(hide yes)
			)
		)
		(property "Val" "5p6"
			(at 130.302 171.45 90)
			(effects
				(font
					(size 1.27 1.27)
					(thickness 0.15)
				)
				(justify right)
			)
		)
		(property "Voltage" "50V"
			(at 156.21 152.4 0)
			(effects
				(font
					(size 1.27 1.27)
				)
				(justify left bottom)
				(hide yes)
			)
		)
		(property "Dielectric" "C0G"
			(at 158.75 152.4 0)
			(effects
				(font
					(size 1.27 1.27)
				)
				(justify left bottom)
				(hide yes)
			)
		)
		(pin "2"
		)
		(pin "1"
		)
		(instances
			(project "OCuLink to 10GbE adapter"
				(path ""
					(reference "C72")
					(unit 1)
				)
			)
		)
	)
	(symbol
		(lib_id "antmicroResistors0402:R_100k_0402")
		(at 130.81 78.74 90)
		(unit 1)
		(exclude_from_sim no)
		(in_bom yes)
		(on_board yes)
		(dnp no)
		(property "Reference" "R88"
			(at 132.334 74.93 90)
			(effects
				(font
					(size 1.27 1.27)
					(thickness 0.15)
				)
				(justify right)
			)
		)
		(property "Value" "R_100k_0402"
			(at 143.51 58.42 0)
			(effects
				(font
					(size 1.27 1.27)
					(thickness 0.15)
				)
				(justify left bottom)
				(hide yes)
			)
		)
		(property "Footprint" "antmicro-footprints:R_0402_1005Metric"
			(at 146.05 58.42 0)
			(effects
				(font
					(size 1.27 1.27)
					(thickness 0.15)
				)
				(justify left bottom)
				(hide yes)
			)
		)
		(property "Datasheet" "https://www.bourns.com/docs/product-datasheets/cr.pdf"
			(at 148.59 58.42 0)
			(effects
				(font
					(size 1.27 1.27)
					(thickness 0.15)
				)
				(justify left bottom)
				(hide yes)
			)
		)
		(property "Description" "SMD Chip Resistor, 100 kohm, ± 1%, 62.5 mW, 0402 [1005 Metric], Thick Film, General Purpose"
			(at 130.81 78.74 0)
			(effects
				(font
					(size 1.27 1.27)
				)
				(hide yes)
			)
		)
		(property "MPN" "CR0402-FX-1003GLF"
			(at 151.13 58.42 0)
			(effects
				(font
					(size 1.27 1.27)
					(thickness 0.15)
				)
				(justify left bottom)
				(hide yes)
			)
		)
		(property "Manufacturer" "Bourns"
			(at 153.67 58.42 0)
			(effects
				(font
					(size 1.27 1.27)
					(thickness 0.15)
				)
				(justify left bottom)
				(hide yes)
			)
		)
		(property "License" "Apache-2.0"
			(at 156.21 58.42 0)
			(effects
				(font
					(size 1.27 1.27)
					(thickness 0.15)
				)
				(justify left bottom)
				(hide yes)
			)
		)
		(property "Author" "Antmicro"
			(at 158.75 58.42 0)
			(effects
				(font
					(size 1.27 1.27)
					(thickness 0.15)
				)
				(justify left bottom)
				(hide yes)
			)
		)
		(property "Val" "100k"
			(at 132.334 77.47 90)
			(effects
				(font
					(size 1.27 1.27)
					(thickness 0.15)
				)
				(justify right)
			)
		)
		(property "Tolerance" "1%"
			(at 140.97 58.42 0)
			(effects
				(font
					(size 1.27 1.27)
				)
				(justify left bottom)
				(hide yes)
			)
		)
		(pin "2"
		)
		(pin "1"
		)
		(instances
			(project "OCuLink to 10GbE adapter"
				(path ""
					(reference "R88")
					(unit 1)
				)
			)
		)
	)
	(symbol
		(lib_id "antmicroTestPoints:TP_0.75mm_SMD")
		(at 92.71 50.8 180)
		(unit 1)
		(exclude_from_sim no)
		(in_bom no)
		(on_board yes)
		(dnp no)
		(property "Reference" "TP1"
			(at 88.392 50.8 0)
			(effects
				(font
					(size 1.27 1.27)
					(thickness 0.15)
				)
				(justify left)
			)
		)
		(property "Value" "TP_0.75mm_SMD"
			(at 82.55 46.99 0)
			(effects
				(font
					(size 1.27 1.27)
					(thickness 0.15)
				)
				(justify left bottom)
				(hide yes)
			)
		)
		(property "Footprint" "antmicro-footprints:TP_SMD_0.75mm"
			(at 82.55 44.45 0)
			(effects
				(font
					(size 1.27 1.27)
					(thickness 0.15)
				)
				(justify left bottom)
				(hide yes)
			)
		)
		(property "Datasheet" ""
			(at 74.93 38.1 0)
			(effects
				(font
					(size 1.27 1.27)
					(thickness 0.15)
				)
				(justify left bottom)
				(hide yes)
			)
		)
		(property "Description" "SMT test point"
			(at 92.71 50.8 0)
			(effects
				(font
					(size 1.27 1.27)
				)
				(hide yes)
			)
		)
		(property "MPN" ""
			(at 81.915 39.37 0)
			(effects
				(font
					(size 1.27 1.27)
					(thickness 0.15)
				)
				(justify left bottom)
				(hide yes)
			)
		)
		(property "Manufacturer" ""
			(at 81.915 44.45 0)
			(effects
				(font
					(size 1.27 1.27)
					(thickness 0.15)
				)
				(justify left bottom)
				(hide yes)
			)
		)
		(property "Author" "Antmicro"
			(at 82.55 41.91 0)
			(effects
				(font
					(size 1.27 1.27)
					(thickness 0.15)
				)
				(justify left bottom)
				(hide yes)
			)
		)
		(property "License" "Apache-2.0"
			(at 82.55 39.37 0)
			(effects
				(font
					(size 1.27 1.27)
					(thickness 0.15)
				)
				(justify left bottom)
				(hide yes)
			)
		)
		(pin "1"
		)
		(instances
			(project ""
				(path ""
					(reference "TP1")
					(unit 1)
				)
			)
		)
	)
	(symbol
		(lib_id "antmicroTestPoints:TP_0.75mm_SMD")
		(at 167.64 167.64 180)
		(unit 1)
		(exclude_from_sim no)
		(in_bom no)
		(on_board yes)
		(dnp no)
		(property "Reference" "TP25"
			(at 163.322 167.64 0)
			(effects
				(font
					(size 1.27 1.27)
					(thickness 0.15)
				)
				(justify left)
			)
		)
		(property "Value" "TP_0.75mm_SMD"
			(at 157.48 163.83 0)
			(effects
				(font
					(size 1.27 1.27)
					(thickness 0.15)
				)
				(justify left bottom)
				(hide yes)
			)
		)
		(property "Footprint" "antmicro-footprints:TP_SMD_0.75mm"
			(at 157.48 161.29 0)
			(effects
				(font
					(size 1.27 1.27)
					(thickness 0.15)
				)
				(justify left bottom)
				(hide yes)
			)
		)
		(property "Datasheet" ""
			(at 149.86 154.94 0)
			(effects
				(font
					(size 1.27 1.27)
					(thickness 0.15)
				)
				(justify left bottom)
				(hide yes)
			)
		)
		(property "Description" "SMT test point"
			(at 167.64 167.64 0)
			(effects
				(font
					(size 1.27 1.27)
				)
				(hide yes)
			)
		)
		(property "MPN" ""
			(at 156.845 156.21 0)
			(effects
				(font
					(size 1.27 1.27)
					(thickness 0.15)
				)
				(justify left bottom)
				(hide yes)
			)
		)
		(property "Manufacturer" ""
			(at 156.845 161.29 0)
			(effects
				(font
					(size 1.27 1.27)
					(thickness 0.15)
				)
				(justify left bottom)
				(hide yes)
			)
		)
		(property "Author" "Antmicro"
			(at 157.48 158.75 0)
			(effects
				(font
					(size 1.27 1.27)
					(thickness 0.15)
				)
				(justify left bottom)
				(hide yes)
			)
		)
		(property "License" "Apache-2.0"
			(at 157.48 156.21 0)
			(effects
				(font
					(size 1.27 1.27)
					(thickness 0.15)
				)
				(justify left bottom)
				(hide yes)
			)
		)
		(pin "1"
		)
		(instances
			(project "OCuLink to 10GbE adapter"
				(path ""
					(reference "TP25")
					(unit 1)
				)
			)
		)
	)
	(symbol
		(lib_id "antmicroCapacitors0402:C_100n_0402")
		(at 97.79 179.07 90)
		(unit 1)
		(exclude_from_sim no)
		(in_bom yes)
		(on_board yes)
		(dnp no)
		(property "Reference" "C76"
			(at 99.822 175.26 90)
			(effects
				(font
					(size 1.27 1.27)
					(thickness 0.15)
				)
				(justify right)
			)
		)
		(property "Value" "C_100n_0402"
			(at 120.65 163.83 0)
			(effects
				(font
					(size 1.27 1.27)
					(thickness 0.15)
				)
				(justify left bottom)
				(hide yes)
			)
		)
		(property "Footprint" "antmicro-footprints:C_0402_1005Metric"
			(at 123.19 163.83 0)
			(effects
				(font
					(size 1.27 1.27)
					(thickness 0.15)
				)
				(justify left bottom)
				(hide yes)
			)
		)
		(property "Datasheet" "https://www.murata.com/products/productdetail?partno=GRM155R61H104KE14%23"
			(at 125.73 163.83 0)
			(effects
				(font
					(size 1.27 1.27)
					(thickness 0.15)
				)
				(justify left bottom)
				(hide yes)
			)
		)
		(property "Description" "SMD Multilayer Ceramic Capacitor, 0.1 µF, 50 V, 0402 [1005 Metric], ± 10%, X5R, GRM Series"
			(at 97.79 179.07 0)
			(effects
				(font
					(size 1.27 1.27)
				)
				(hide yes)
			)
		)
		(property "MPN" "GRM155R61H104KE14D"
			(at 128.27 163.83 0)
			(effects
				(font
					(size 1.27 1.27)
					(thickness 0.15)
				)
				(justify left bottom)
				(hide yes)
			)
		)
		(property "Val" "100n"
			(at 99.822 177.8 90)
			(effects
				(font
					(size 1.27 1.27)
					(thickness 0.15)
				)
				(justify right)
			)
		)
		(property "Voltage" "50V"
			(at 107.95 163.83 0)
			(effects
				(font
					(size 1.27 1.27)
					(thickness 0.15)
				)
				(justify left bottom)
				(hide yes)
			)
		)
		(property "Dielectric" "X5R"
			(at 110.49 163.83 0)
			(effects
				(font
					(size 1.27 1.27)
					(thickness 0.15)
				)
				(justify left bottom)
				(hide yes)
			)
		)
		(property "Manufacturer" "Murata"
			(at 113.03 163.83 0)
			(effects
				(font
					(size 1.27 1.27)
					(thickness 0.15)
				)
				(justify left bottom)
				(hide yes)
			)
		)
		(property "License" "Apache-2.0"
			(at 115.57 163.83 0)
			(effects
				(font
					(size 1.27 1.27)
					(thickness 0.15)
				)
				(justify left bottom)
				(hide yes)
			)
		)
		(property "Author" "Antmicro"
			(at 118.11 163.83 0)
			(effects
				(font
					(size 1.27 1.27)
					(thickness 0.15)
				)
				(justify left bottom)
				(hide yes)
			)
		)
		(pin "2"
		)
		(pin "1"
		)
		(instances
			(project "OCuLink to 10GbE adapter"
				(path ""
					(reference "C76")
					(unit 1)
				)
			)
		)
	)
	(symbol
		(lib_id "antmicropower:GND")
		(at 139.7 81.28 0)
		(unit 1)
		(exclude_from_sim no)
		(in_bom yes)
		(on_board yes)
		(dnp no)
		(property "Reference" "#PWR0261"
			(at 148.59 83.82 0)
			(effects
				(font
					(size 1.27 1.27)
					(thickness 0.15)
				)
				(justify left bottom)
				(hide yes)
			)
		)
		(property "Value" "GND"
			(at 139.7 85.09 0)
			(effects
				(font
					(size 1.27 1.27)
					(thickness 0.15)
				)
			)
		)
		(property "Footprint" ""
			(at 148.59 88.9 0)
			(effects
				(font
					(size 1.27 1.27)
					(thickness 0.15)
				)
				(justify left bottom)
				(hide yes)
			)
		)
		(property "Datasheet" ""
			(at 148.59 93.98 0)
			(effects
				(font
					(size 1.27 1.27)
					(thickness 0.15)
				)
				(justify left bottom)
				(hide yes)
			)
		)
		(property "Description" ""
			(at 139.7 81.28 0)
			(effects
				(font
					(size 1.27 1.27)
				)
				(hide yes)
			)
		)
		(property "Author" "Antmicro"
			(at 148.59 88.9 0)
			(effects
				(font
					(size 1.27 1.27)
					(thickness 0.15)
				)
				(justify left bottom)
				(hide yes)
			)
		)
		(property "License" "Apache-2.0"
			(at 148.59 91.44 0)
			(effects
				(font
					(size 1.27 1.27)
					(thickness 0.15)
				)
				(justify left bottom)
				(hide yes)
			)
		)
		(pin "1"
		)
		(instances
			(project "OCuLink to 10GbE adapter"
				(path ""
					(reference "#PWR0261")
					(unit 1)
				)
			)
		)
	)
	(symbol
		(lib_id "antmicroTestPoints:TP_0.75mm_SMD")
		(at 92.71 60.96 180)
		(unit 1)
		(exclude_from_sim no)
		(in_bom no)
		(on_board yes)
		(dnp no)
		(property "Reference" "TP5"
			(at 88.392 60.96 0)
			(effects
				(font
					(size 1.27 1.27)
					(thickness 0.15)
				)
				(justify left)
			)
		)
		(property "Value" "TP_0.75mm_SMD"
			(at 82.55 57.15 0)
			(effects
				(font
					(size 1.27 1.27)
					(thickness 0.15)
				)
				(justify left bottom)
				(hide yes)
			)
		)
		(property "Footprint" "antmicro-footprints:TP_SMD_0.75mm"
			(at 82.55 54.61 0)
			(effects
				(font
					(size 1.27 1.27)
					(thickness 0.15)
				)
				(justify left bottom)
				(hide yes)
			)
		)
		(property "Datasheet" ""
			(at 74.93 48.26 0)
			(effects
				(font
					(size 1.27 1.27)
					(thickness 0.15)
				)
				(justify left bottom)
				(hide yes)
			)
		)
		(property "Description" "SMT test point"
			(at 92.71 60.96 0)
			(effects
				(font
					(size 1.27 1.27)
				)
				(hide yes)
			)
		)
		(property "MPN" ""
			(at 81.915 49.53 0)
			(effects
				(font
					(size 1.27 1.27)
					(thickness 0.15)
				)
				(justify left bottom)
				(hide yes)
			)
		)
		(property "Manufacturer" ""
			(at 81.915 54.61 0)
			(effects
				(font
					(size 1.27 1.27)
					(thickness 0.15)
				)
				(justify left bottom)
				(hide yes)
			)
		)
		(property "Author" "Antmicro"
			(at 82.55 52.07 0)
			(effects
				(font
					(size 1.27 1.27)
					(thickness 0.15)
				)
				(justify left bottom)
				(hide yes)
			)
		)
		(property "License" "Apache-2.0"
			(at 82.55 49.53 0)
			(effects
				(font
					(size 1.27 1.27)
					(thickness 0.15)
				)
				(justify left bottom)
				(hide yes)
			)
		)
		(pin "1"
		)
		(instances
			(project "OCuLink to 10GbE adapter"
				(path ""
					(reference "TP5")
					(unit 1)
				)
			)
		)
	)
	(symbol
		(lib_id "antmicroResistors0402:R_100k_0402")
		(at 137.16 48.26 90)
		(unit 1)
		(exclude_from_sim no)
		(in_bom yes)
		(on_board yes)
		(dnp no)
		(property "Reference" "R81"
			(at 138.684 44.45 90)
			(effects
				(font
					(size 1.27 1.27)
					(thickness 0.15)
				)
				(justify right)
			)
		)
		(property "Value" "R_100k_0402"
			(at 149.86 27.94 0)
			(effects
				(font
					(size 1.27 1.27)
					(thickness 0.15)
				)
				(justify left bottom)
				(hide yes)
			)
		)
		(property "Footprint" "antmicro-footprints:R_0402_1005Metric"
			(at 152.4 27.94 0)
			(effects
				(font
					(size 1.27 1.27)
					(thickness 0.15)
				)
				(justify left bottom)
				(hide yes)
			)
		)
		(property "Datasheet" "https://www.bourns.com/docs/product-datasheets/cr.pdf"
			(at 154.94 27.94 0)
			(effects
				(font
					(size 1.27 1.27)
					(thickness 0.15)
				)
				(justify left bottom)
				(hide yes)
			)
		)
		(property "Description" "SMD Chip Resistor, 100 kohm, ± 1%, 62.5 mW, 0402 [1005 Metric], Thick Film, General Purpose"
			(at 137.16 48.26 0)
			(effects
				(font
					(size 1.27 1.27)
				)
				(hide yes)
			)
		)
		(property "MPN" "CR0402-FX-1003GLF"
			(at 157.48 27.94 0)
			(effects
				(font
					(size 1.27 1.27)
					(thickness 0.15)
				)
				(justify left bottom)
				(hide yes)
			)
		)
		(property "Manufacturer" "Bourns"
			(at 160.02 27.94 0)
			(effects
				(font
					(size 1.27 1.27)
					(thickness 0.15)
				)
				(justify left bottom)
				(hide yes)
			)
		)
		(property "License" "Apache-2.0"
			(at 162.56 27.94 0)
			(effects
				(font
					(size 1.27 1.27)
					(thickness 0.15)
				)
				(justify left bottom)
				(hide yes)
			)
		)
		(property "Author" "Antmicro"
			(at 165.1 27.94 0)
			(effects
				(font
					(size 1.27 1.27)
					(thickness 0.15)
				)
				(justify left bottom)
				(hide yes)
			)
		)
		(property "Val" "100k"
			(at 138.684 46.99 90)
			(effects
				(font
					(size 1.27 1.27)
					(thickness 0.15)
				)
				(justify right)
			)
		)
		(property "Tolerance" "1%"
			(at 147.32 27.94 0)
			(effects
				(font
					(size 1.27 1.27)
				)
				(justify left bottom)
				(hide yes)
			)
		)
		(pin "2"
		)
		(pin "1"
		)
		(instances
			(project "OCuLink to 10GbE adapter"
				(path ""
					(reference "R81")
					(unit 1)
				)
			)
		)
	)
	(symbol
		(lib_id "antmicroResistors0402:R_10k_0402")
		(at 135.89 104.14 90)
		(unit 1)
		(exclude_from_sim no)
		(in_bom yes)
		(on_board yes)
		(dnp no)
		(property "Reference" "R98"
			(at 137.16 100.33 90)
			(effects
				(font
					(size 1.27 1.27)
					(thickness 0.15)
				)
				(justify right)
			)
		)
		(property "Value" "R_10k_0402"
			(at 148.59 83.82 0)
			(effects
				(font
					(size 1.27 1.27)
					(thickness 0.15)
				)
				(justify left bottom)
				(hide yes)
			)
		)
		(property "Footprint" "antmicro-footprints:R_0402_1005Metric"
			(at 151.13 83.82 0)
			(effects
				(font
					(size 1.27 1.27)
					(thickness 0.15)
				)
				(justify left bottom)
				(hide yes)
			)
		)
		(property "Datasheet" "https://www.bourns.com/docs/product-datasheets/cr.pdf"
			(at 153.67 83.82 0)
			(effects
				(font
					(size 1.27 1.27)
					(thickness 0.15)
				)
				(justify left bottom)
				(hide yes)
			)
		)
		(property "Description" "SMD Chip Resistor, 10 kohm, ± 1%, 62.5 mW, 0402 [1005 Metric], Thick Film, General Purpose"
			(at 135.89 104.14 0)
			(effects
				(font
					(size 1.27 1.27)
				)
				(hide yes)
			)
		)
		(property "MPN" "CR0402-FX-1002GLF"
			(at 156.21 83.82 0)
			(effects
				(font
					(size 1.27 1.27)
					(thickness 0.15)
				)
				(justify left bottom)
				(hide yes)
			)
		)
		(property "Manufacturer" "Bourns"
			(at 158.75 83.82 0)
			(effects
				(font
					(size 1.27 1.27)
					(thickness 0.15)
				)
				(justify left bottom)
				(hide yes)
			)
		)
		(property "License" "Apache-2.0"
			(at 161.29 83.82 0)
			(effects
				(font
					(size 1.27 1.27)
					(thickness 0.15)
				)
				(justify left bottom)
				(hide yes)
			)
		)
		(property "Author" "Antmicro"
			(at 163.83 83.82 0)
			(effects
				(font
					(size 1.27 1.27)
					(thickness 0.15)
				)
				(justify left bottom)
				(hide yes)
			)
		)
		(property "Val" "10k"
			(at 137.16 102.87 90)
			(effects
				(font
					(size 1.27 1.27)
					(thickness 0.15)
				)
				(justify right)
			)
		)
		(property "Tolerance" "1%"
			(at 146.05 83.82 0)
			(effects
				(font
					(size 1.27 1.27)
				)
				(justify left bottom)
				(hide yes)
			)
		)
		(pin "2"
		)
		(pin "1"
		)
		(instances
			(project "OCuLink to 10GbE adapter"
				(path ""
					(reference "R98")
					(unit 1)
				)
			)
		)
	)
	(symbol
		(lib_id "antmicroResistors0402:R_10k_0402")
		(at 118.11 104.14 90)
		(unit 1)
		(exclude_from_sim no)
		(in_bom no)
		(on_board yes)
		(dnp yes)
		(property "Reference" "R96"
			(at 119.38 100.33 90)
			(effects
				(font
					(size 1.27 1.27)
					(thickness 0.15)
				)
				(justify right)
			)
		)
		(property "Value" "R_10k_0402"
			(at 130.81 83.82 0)
			(effects
				(font
					(size 1.27 1.27)
					(thickness 0.15)
				)
				(justify left bottom)
				(hide yes)
			)
		)
		(property "Footprint" "antmicro-footprints:R_0402_1005Metric"
			(at 133.35 83.82 0)
			(effects
				(font
					(size 1.27 1.27)
					(thickness 0.15)
				)
				(justify left bottom)
				(hide yes)
			)
		)
		(property "Datasheet" "https://www.bourns.com/docs/product-datasheets/cr.pdf"
			(at 135.89 83.82 0)
			(effects
				(font
					(size 1.27 1.27)
					(thickness 0.15)
				)
				(justify left bottom)
				(hide yes)
			)
		)
		(property "Description" "SMD Chip Resistor, 10 kohm, ± 1%, 62.5 mW, 0402 [1005 Metric], Thick Film, General Purpose"
			(at 118.11 104.14 0)
			(effects
				(font
					(size 1.27 1.27)
				)
				(hide yes)
			)
		)
		(property "MPN" "CR0402-FX-1002GLF"
			(at 138.43 83.82 0)
			(effects
				(font
					(size 1.27 1.27)
					(thickness 0.15)
				)
				(justify left bottom)
				(hide yes)
			)
		)
		(property "Manufacturer" "Bourns"
			(at 140.97 83.82 0)
			(effects
				(font
					(size 1.27 1.27)
					(thickness 0.15)
				)
				(justify left bottom)
				(hide yes)
			)
		)
		(property "License" "Apache-2.0"
			(at 143.51 83.82 0)
			(effects
				(font
					(size 1.27 1.27)
					(thickness 0.15)
				)
				(justify left bottom)
				(hide yes)
			)
		)
		(property "Author" "Antmicro"
			(at 146.05 83.82 0)
			(effects
				(font
					(size 1.27 1.27)
					(thickness 0.15)
				)
				(justify left bottom)
				(hide yes)
			)
		)
		(property "Val" "10k"
			(at 119.38 102.87 90)
			(effects
				(font
					(size 1.27 1.27)
					(thickness 0.15)
				)
				(justify right)
			)
		)
		(property "Tolerance" "1%"
			(at 128.27 83.82 0)
			(effects
				(font
					(size 1.27 1.27)
				)
				(justify left bottom)
				(hide yes)
			)
		)
		(pin "2"
		)
		(pin "1"
		)
		(instances
			(project "OCuLink to 10GbE adapter"
				(path ""
					(reference "R96")
					(unit 1)
				)
			)
		)
	)
	(symbol
		(lib_id "antmicropower:GND")
		(at 148.59 175.26 0)
		(unit 1)
		(exclude_from_sim no)
		(in_bom yes)
		(on_board yes)
		(dnp no)
		(property "Reference" "#PWR0276"
			(at 157.48 177.8 0)
			(effects
				(font
					(size 1.27 1.27)
					(thickness 0.15)
				)
				(justify left bottom)
				(hide yes)
			)
		)
		(property "Value" "GND"
			(at 148.59 179.07 0)
			(effects
				(font
					(size 1.27 1.27)
					(thickness 0.15)
				)
			)
		)
		(property "Footprint" ""
			(at 157.48 182.88 0)
			(effects
				(font
					(size 1.27 1.27)
					(thickness 0.15)
				)
				(justify left bottom)
				(hide yes)
			)
		)
		(property "Datasheet" ""
			(at 157.48 187.96 0)
			(effects
				(font
					(size 1.27 1.27)
					(thickness 0.15)
				)
				(justify left bottom)
				(hide yes)
			)
		)
		(property "Description" ""
			(at 148.59 175.26 0)
			(effects
				(font
					(size 1.27 1.27)
				)
				(hide yes)
			)
		)
		(property "Author" "Antmicro"
			(at 157.48 182.88 0)
			(effects
				(font
					(size 1.27 1.27)
					(thickness 0.15)
				)
				(justify left bottom)
				(hide yes)
			)
		)
		(property "License" "Apache-2.0"
			(at 157.48 185.42 0)
			(effects
				(font
					(size 1.27 1.27)
					(thickness 0.15)
				)
				(justify left bottom)
				(hide yes)
			)
		)
		(pin "1"
		)
		(instances
			(project "OCuLink to 10GbE adapter"
				(path ""
					(reference "#PWR0276")
					(unit 1)
				)
			)
		)
	)
	(symbol
		(lib_id "antmicroResistors0402:R_1k_0402")
		(at 172.72 185.42 90)
		(unit 1)
		(exclude_from_sim no)
		(in_bom yes)
		(on_board yes)
		(dnp no)
		(property "Reference" "R116"
			(at 174.244 181.61 90)
			(effects
				(font
					(size 1.27 1.27)
					(thickness 0.15)
				)
				(justify right)
			)
		)
		(property "Value" "R_1k_0402"
			(at 185.42 165.1 0)
			(effects
				(font
					(size 1.27 1.27)
					(thickness 0.15)
				)
				(justify left bottom)
				(hide yes)
			)
		)
		(property "Footprint" "antmicro-footprints:R_0402_1005Metric"
			(at 187.96 165.1 0)
			(effects
				(font
					(size 1.27 1.27)
					(thickness 0.15)
				)
				(justify left bottom)
				(hide yes)
			)
		)
		(property "Datasheet" "https://www.bourns.com/docs/product-datasheets/cr.pdf"
			(at 190.5 165.1 0)
			(effects
				(font
					(size 1.27 1.27)
					(thickness 0.15)
				)
				(justify left bottom)
				(hide yes)
			)
		)
		(property "Description" "SMD Chip Resistor, 1 kohm, ± 1%, 63 mW, 0402 [1005 Metric], Thick Film, General Purpose"
			(at 172.72 185.42 0)
			(effects
				(font
					(size 1.27 1.27)
				)
				(hide yes)
			)
		)
		(property "MPN" "CR0402-FX-1001GLF"
			(at 193.04 165.1 0)
			(effects
				(font
					(size 1.27 1.27)
					(thickness 0.15)
				)
				(justify left bottom)
				(hide yes)
			)
		)
		(property "Manufacturer" "Bourns"
			(at 195.58 165.1 0)
			(effects
				(font
					(size 1.27 1.27)
					(thickness 0.15)
				)
				(justify left bottom)
				(hide yes)
			)
		)
		(property "License" "Apache-2.0"
			(at 198.12 165.1 0)
			(effects
				(font
					(size 1.27 1.27)
					(thickness 0.15)
				)
				(justify left bottom)
				(hide yes)
			)
		)
		(property "Author" "Antmicro"
			(at 200.66 165.1 0)
			(effects
				(font
					(size 1.27 1.27)
					(thickness 0.15)
				)
				(justify left bottom)
				(hide yes)
			)
		)
		(property "Val" "1k"
			(at 174.244 184.15 90)
			(effects
				(font
					(size 1.27 1.27)
					(thickness 0.15)
				)
				(justify right)
			)
		)
		(property "Tolerance" "1%"
			(at 182.88 165.1 0)
			(effects
				(font
					(size 1.27 1.27)
				)
				(justify left bottom)
				(hide yes)
			)
		)
		(pin "2"
		)
		(pin "1"
		)
		(instances
			(project ""
				(path ""
					(reference "R116")
					(unit 1)
				)
			)
		)
	)
	(symbol
		(lib_id "antmicroTestPoints:TP_0.75mm_SMD")
		(at 92.71 71.12 180)
		(unit 1)
		(exclude_from_sim no)
		(in_bom no)
		(on_board yes)
		(dnp no)
		(property "Reference" "TP9"
			(at 88.392 71.12 0)
			(effects
				(font
					(size 1.27 1.27)
					(thickness 0.15)
				)
				(justify left)
			)
		)
		(property "Value" "TP_0.75mm_SMD"
			(at 82.55 67.31 0)
			(effects
				(font
					(size 1.27 1.27)
					(thickness 0.15)
				)
				(justify left bottom)
				(hide yes)
			)
		)
		(property "Footprint" "antmicro-footprints:TP_SMD_0.75mm"
			(at 82.55 64.77 0)
			(effects
				(font
					(size 1.27 1.27)
					(thickness 0.15)
				)
				(justify left bottom)
				(hide yes)
			)
		)
		(property "Datasheet" ""
			(at 74.93 58.42 0)
			(effects
				(font
					(size 1.27 1.27)
					(thickness 0.15)
				)
				(justify left bottom)
				(hide yes)
			)
		)
		(property "Description" "SMT test point"
			(at 92.71 71.12 0)
			(effects
				(font
					(size 1.27 1.27)
				)
				(hide yes)
			)
		)
		(property "MPN" ""
			(at 81.915 59.69 0)
			(effects
				(font
					(size 1.27 1.27)
					(thickness 0.15)
				)
				(justify left bottom)
				(hide yes)
			)
		)
		(property "Manufacturer" ""
			(at 81.915 64.77 0)
			(effects
				(font
					(size 1.27 1.27)
					(thickness 0.15)
				)
				(justify left bottom)
				(hide yes)
			)
		)
		(property "Author" "Antmicro"
			(at 82.55 62.23 0)
			(effects
				(font
					(size 1.27 1.27)
					(thickness 0.15)
				)
				(justify left bottom)
				(hide yes)
			)
		)
		(property "License" "Apache-2.0"
			(at 82.55 59.69 0)
			(effects
				(font
					(size 1.27 1.27)
					(thickness 0.15)
				)
				(justify left bottom)
				(hide yes)
			)
		)
		(pin "1"
		)
		(instances
			(project "OCuLink to 10GbE adapter"
				(path ""
					(reference "TP9")
					(unit 1)
				)
			)
		)
	)
	(symbol
		(lib_id "antmicroLogicTranslatorsLevelShifters:NTS0102_TSSOP")
		(at 90.17 185.42 0)
		(mirror y)
		(unit 1)
		(exclude_from_sim no)
		(in_bom yes)
		(on_board yes)
		(dnp no)
		(fields_autoplaced yes)
		(property "Reference" "U8"
			(at 80.01 177.8 0)
			(effects
				(font
					(size 1.27 1.27)
					(thickness 0.15)
				)
			)
		)
		(property "Value" "NTS0102_TSSOP"
			(at 54.61 191.77 0)
			(effects
				(font
					(size 1.27 1.27)
					(thickness 0.15)
				)
				(justify left bottom)
				(hide yes)
			)
		)
		(property "Footprint" "antmicro-footprints:TSSOP-8_3x3mm_P0.65mm"
			(at 54.61 194.31 0)
			(effects
				(font
					(size 1.27 1.27)
					(thickness 0.15)
				)
				(justify left bottom)
				(hide yes)
			)
		)
		(property "Datasheet" "https://www.mouser.com/datasheet/2/302/NTS0102-1127324.pdf"
			(at 54.61 196.85 0)
			(effects
				(font
					(size 1.27 1.27)
					(thickness 0.15)
				)
				(justify left bottom)
				(hide yes)
			)
		)
		(property "Description" "Transceiver, 1.65 V to 3.6 V, TSSOP-8"
			(at 90.17 185.42 0)
			(effects
				(font
					(size 1.27 1.27)
				)
				(hide yes)
			)
		)
		(property "MPN" "NTS0102DP"
			(at 80.01 180.34 0)
			(effects
				(font
					(size 1.27 1.27)
					(thickness 0.15)
				)
			)
		)
		(property "Manufacturer" "NXP"
			(at 54.61 201.93 0)
			(effects
				(font
					(size 1.27 1.27)
					(thickness 0.15)
				)
				(justify left bottom)
				(hide yes)
			)
		)
		(property "Author" "Antmicro"
			(at 54.61 204.47 0)
			(effects
				(font
					(size 1.27 1.27)
					(thickness 0.15)
				)
				(justify left bottom)
				(hide yes)
			)
		)
		(property "License" "Apache-2.0"
			(at 54.61 207.01 0)
			(effects
				(font
					(size 1.27 1.27)
					(thickness 0.15)
				)
				(justify left bottom)
				(hide yes)
			)
		)
		(pin "5"
		)
		(pin "3"
		)
		(pin "1"
		)
		(pin "6"
		)
		(pin "7"
		)
		(pin "4"
		)
		(pin "2"
		)
		(pin "8"
		)
		(instances
			(project "OCuLink to 10GbE adapter"
				(path ""
					(reference "U8")
					(unit 1)
				)
			)
		)
	)
	(symbol
		(lib_id "antmicropower:+3V3_AON")
		(at 44.45 93.98 0)
		(unit 1)
		(exclude_from_sim no)
		(in_bom yes)
		(on_board yes)
		(dnp no)
		(property "Reference" "#PWR0107"
			(at 44.45 97.79 0)
			(effects
				(font
					(size 1.27 1.27)
				)
				(hide yes)
			)
		)
		(property "Value" "+3V3_AUX"
			(at 44.45 90.17 0)
			(effects
				(font
					(size 1.27 1.27)
				)
			)
		)
		(property "Footprint" ""
			(at 44.45 93.98 0)
			(effects
				(font
					(size 1.27 1.27)
				)
				(hide yes)
			)
		)
		(property "Datasheet" ""
			(at 44.45 93.98 0)
			(effects
				(font
					(size 1.27 1.27)
				)
				(hide yes)
			)
		)
		(property "Description" ""
			(at 44.45 100.33 0)
			(effects
				(font
					(size 1.27 1.27)
				)
				(justify left bottom)
				(hide yes)
			)
		)
		(pin "1"
		)
		(instances
			(project "OCuLink to 10GbE adapter"
				(path ""
					(reference "#PWR0107")
					(unit 1)
				)
			)
		)
	)
	(symbol
		(lib_id "antmicropower:GND")
		(at 137.16 175.26 0)
		(unit 1)
		(exclude_from_sim no)
		(in_bom yes)
		(on_board yes)
		(dnp no)
		(property "Reference" "#PWR097"
			(at 146.05 177.8 0)
			(effects
				(font
					(size 1.27 1.27)
					(thickness 0.15)
				)
				(justify left bottom)
				(hide yes)
			)
		)
		(property "Value" "GND"
			(at 137.16 179.07 0)
			(effects
				(font
					(size 1.27 1.27)
					(thickness 0.15)
				)
			)
		)
		(property "Footprint" ""
			(at 146.05 182.88 0)
			(effects
				(font
					(size 1.27 1.27)
					(thickness 0.15)
				)
				(justify left bottom)
				(hide yes)
			)
		)
		(property "Datasheet" ""
			(at 146.05 187.96 0)
			(effects
				(font
					(size 1.27 1.27)
					(thickness 0.15)
				)
				(justify left bottom)
				(hide yes)
			)
		)
		(property "Description" ""
			(at 137.16 175.26 0)
			(effects
				(font
					(size 1.27 1.27)
				)
				(hide yes)
			)
		)
		(property "Author" "Antmicro"
			(at 146.05 182.88 0)
			(effects
				(font
					(size 1.27 1.27)
					(thickness 0.15)
				)
				(justify left bottom)
				(hide yes)
			)
		)
		(property "License" "Apache-2.0"
			(at 146.05 185.42 0)
			(effects
				(font
					(size 1.27 1.27)
					(thickness 0.15)
				)
				(justify left bottom)
				(hide yes)
			)
		)
		(pin "1"
		)
		(instances
			(project "OCuLink to 10GbE adapter"
				(path ""
					(reference "#PWR097")
					(unit 1)
				)
			)
		)
	)
	(symbol
		(lib_id "antmicropower:+3V3")
		(at 67.31 210.82 0)
		(mirror y)
		(unit 1)
		(exclude_from_sim no)
		(in_bom yes)
		(on_board yes)
		(dnp no)
		(property "Reference" "#PWR0100"
			(at 52.07 210.82 0)
			(effects
				(font
					(size 1.27 1.27)
					(thickness 0.15)
				)
				(justify left bottom)
				(hide yes)
			)
		)
		(property "Value" "+3V3"
			(at 67.31 207.01 0)
			(effects
				(font
					(size 1.27 1.27)
					(thickness 0.15)
				)
			)
		)
		(property "Footprint" ""
			(at 52.07 218.44 0)
			(effects
				(font
					(size 1.27 1.27)
					(thickness 0.15)
				)
				(justify left bottom)
				(hide yes)
			)
		)
		(property "Datasheet" ""
			(at 52.07 220.98 0)
			(effects
				(font
					(size 1.27 1.27)
					(thickness 0.15)
				)
				(justify left bottom)
				(hide yes)
			)
		)
		(property "Description" ""
			(at 67.31 210.82 0)
			(effects
				(font
					(size 1.27 1.27)
				)
				(hide yes)
			)
		)
		(property "Author" "Antmicro"
			(at 52.07 213.36 0)
			(effects
				(font
					(size 1.27 1.27)
					(thickness 0.15)
				)
				(justify left bottom)
				(hide yes)
			)
		)
		(property "License" "Apache-2.0"
			(at 52.07 215.9 0)
			(effects
				(font
					(size 1.27 1.27)
					(thickness 0.15)
				)
				(justify left bottom)
				(hide yes)
			)
		)
		(pin "1"
		)
		(instances
			(project "OCuLink to 10GbE adapter"
				(path ""
					(reference "#PWR0100")
					(unit 1)
				)
			)
		)
	)
	(symbol
		(lib_id "antmicroResistors0402:R_10k_0402")
		(at 154.94 104.14 90)
		(unit 1)
		(exclude_from_sim no)
		(in_bom yes)
		(on_board yes)
		(dnp no)
		(property "Reference" "R100"
			(at 156.21 100.33 90)
			(effects
				(font
					(size 1.27 1.27)
					(thickness 0.15)
				)
				(justify right)
			)
		)
		(property "Value" "R_10k_0402"
			(at 167.64 83.82 0)
			(effects
				(font
					(size 1.27 1.27)
					(thickness 0.15)
				)
				(justify left bottom)
				(hide yes)
			)
		)
		(property "Footprint" "antmicro-footprints:R_0402_1005Metric"
			(at 170.18 83.82 0)
			(effects
				(font
					(size 1.27 1.27)
					(thickness 0.15)
				)
				(justify left bottom)
				(hide yes)
			)
		)
		(property "Datasheet" "https://www.bourns.com/docs/product-datasheets/cr.pdf"
			(at 172.72 83.82 0)
			(effects
				(font
					(size 1.27 1.27)
					(thickness 0.15)
				)
				(justify left bottom)
				(hide yes)
			)
		)
		(property "Description" "SMD Chip Resistor, 10 kohm, ± 1%, 62.5 mW, 0402 [1005 Metric], Thick Film, General Purpose"
			(at 154.94 104.14 0)
			(effects
				(font
					(size 1.27 1.27)
				)
				(hide yes)
			)
		)
		(property "MPN" "CR0402-FX-1002GLF"
			(at 175.26 83.82 0)
			(effects
				(font
					(size 1.27 1.27)
					(thickness 0.15)
				)
				(justify left bottom)
				(hide yes)
			)
		)
		(property "Manufacturer" "Bourns"
			(at 177.8 83.82 0)
			(effects
				(font
					(size 1.27 1.27)
					(thickness 0.15)
				)
				(justify left bottom)
				(hide yes)
			)
		)
		(property "License" "Apache-2.0"
			(at 180.34 83.82 0)
			(effects
				(font
					(size 1.27 1.27)
					(thickness 0.15)
				)
				(justify left bottom)
				(hide yes)
			)
		)
		(property "Author" "Antmicro"
			(at 182.88 83.82 0)
			(effects
				(font
					(size 1.27 1.27)
					(thickness 0.15)
				)
				(justify left bottom)
				(hide yes)
			)
		)
		(property "Val" "10k"
			(at 156.21 102.87 90)
			(effects
				(font
					(size 1.27 1.27)
					(thickness 0.15)
				)
				(justify right)
			)
		)
		(property "Tolerance" "1%"
			(at 165.1 83.82 0)
			(effects
				(font
					(size 1.27 1.27)
				)
				(justify left bottom)
				(hide yes)
			)
		)
		(pin "2"
		)
		(pin "1"
		)
		(instances
			(project ""
				(path ""
					(reference "R100")
					(unit 1)
				)
			)
		)
	)
	(symbol
		(lib_id "antmicropower:+1V8")
		(at 267.97 196.85 0)
		(unit 1)
		(exclude_from_sim no)
		(in_bom yes)
		(on_board yes)
		(dnp no)
		(property "Reference" "#PWR0278"
			(at 283.21 199.39 0)
			(effects
				(font
					(size 1.27 1.27)
					(thickness 0.15)
				)
				(justify left bottom)
				(hide yes)
			)
		)
		(property "Value" "+1V88"
			(at 267.97 193.04 0)
			(effects
				(font
					(size 1.27 1.27)
					(thickness 0.15)
				)
			)
		)
		(property "Footprint" ""
			(at 283.21 204.47 0)
			(effects
				(font
					(size 1.27 1.27)
					(thickness 0.15)
				)
				(justify left bottom)
				(hide yes)
			)
		)
		(property "Datasheet" ""
			(at 283.21 207.01 0)
			(effects
				(font
					(size 1.27 1.27)
					(thickness 0.15)
				)
				(justify left bottom)
				(hide yes)
			)
		)
		(property "Description" ""
			(at 267.97 196.85 0)
			(effects
				(font
					(size 1.27 1.27)
				)
				(hide yes)
			)
		)
		(property "Author" "Antmicro"
			(at 283.21 201.93 0)
			(effects
				(font
					(size 1.27 1.27)
					(thickness 0.15)
				)
				(justify left bottom)
				(hide yes)
			)
		)
		(property "License" "Apache-2.0"
			(at 283.21 204.47 0)
			(effects
				(font
					(size 1.27 1.27)
					(thickness 0.15)
				)
				(justify left bottom)
				(hide yes)
			)
		)
		(pin "1"
		)
		(instances
			(project "OCuLink to 10GbE adapter"
				(path ""
					(reference "#PWR0278")
					(unit 1)
				)
			)
		)
	)
	(symbol
		(lib_id "antmicropower:GND")
		(at 121.92 81.28 0)
		(unit 1)
		(exclude_from_sim no)
		(in_bom yes)
		(on_board yes)
		(dnp no)
		(property "Reference" "#PWR0259"
			(at 130.81 83.82 0)
			(effects
				(font
					(size 1.27 1.27)
					(thickness 0.15)
				)
				(justify left bottom)
				(hide yes)
			)
		)
		(property "Value" "GND"
			(at 121.92 85.09 0)
			(effects
				(font
					(size 1.27 1.27)
					(thickness 0.15)
				)
			)
		)
		(property "Footprint" ""
			(at 130.81 88.9 0)
			(effects
				(font
					(size 1.27 1.27)
					(thickness 0.15)
				)
				(justify left bottom)
				(hide yes)
			)
		)
		(property "Datasheet" ""
			(at 130.81 93.98 0)
			(effects
				(font
					(size 1.27 1.27)
					(thickness 0.15)
				)
				(justify left bottom)
				(hide yes)
			)
		)
		(property "Description" ""
			(at 121.92 81.28 0)
			(effects
				(font
					(size 1.27 1.27)
				)
				(hide yes)
			)
		)
		(property "Author" "Antmicro"
			(at 130.81 88.9 0)
			(effects
				(font
					(size 1.27 1.27)
					(thickness 0.15)
				)
				(justify left bottom)
				(hide yes)
			)
		)
		(property "License" "Apache-2.0"
			(at 130.81 91.44 0)
			(effects
				(font
					(size 1.27 1.27)
					(thickness 0.15)
				)
				(justify left bottom)
				(hide yes)
			)
		)
		(pin "1"
		)
		(instances
			(project "OCuLink to 10GbE adapter"
				(path ""
					(reference "#PWR0259")
					(unit 1)
				)
			)
		)
	)
	(symbol
		(lib_id "antmicroResistors0402:R_100k_0402")
		(at 139.7 78.74 90)
		(unit 1)
		(exclude_from_sim no)
		(in_bom yes)
		(on_board yes)
		(dnp no)
		(property "Reference" "R89"
			(at 141.224 74.93 90)
			(effects
				(font
					(size 1.27 1.27)
					(thickness 0.15)
				)
				(justify right)
			)
		)
		(property "Value" "R_100k_0402"
			(at 152.4 58.42 0)
			(effects
				(font
					(size 1.27 1.27)
					(thickness 0.15)
				)
				(justify left bottom)
				(hide yes)
			)
		)
		(property "Footprint" "antmicro-footprints:R_0402_1005Metric"
			(at 154.94 58.42 0)
			(effects
				(font
					(size 1.27 1.27)
					(thickness 0.15)
				)
				(justify left bottom)
				(hide yes)
			)
		)
		(property "Datasheet" "https://www.bourns.com/docs/product-datasheets/cr.pdf"
			(at 157.48 58.42 0)
			(effects
				(font
					(size 1.27 1.27)
					(thickness 0.15)
				)
				(justify left bottom)
				(hide yes)
			)
		)
		(property "Description" "SMD Chip Resistor, 100 kohm, ± 1%, 62.5 mW, 0402 [1005 Metric], Thick Film, General Purpose"
			(at 139.7 78.74 0)
			(effects
				(font
					(size 1.27 1.27)
				)
				(hide yes)
			)
		)
		(property "MPN" "CR0402-FX-1003GLF"
			(at 160.02 58.42 0)
			(effects
				(font
					(size 1.27 1.27)
					(thickness 0.15)
				)
				(justify left bottom)
				(hide yes)
			)
		)
		(property "Manufacturer" "Bourns"
			(at 162.56 58.42 0)
			(effects
				(font
					(size 1.27 1.27)
					(thickness 0.15)
				)
				(justify left bottom)
				(hide yes)
			)
		)
		(property "License" "Apache-2.0"
			(at 165.1 58.42 0)
			(effects
				(font
					(size 1.27 1.27)
					(thickness 0.15)
				)
				(justify left bottom)
				(hide yes)
			)
		)
		(property "Author" "Antmicro"
			(at 167.64 58.42 0)
			(effects
				(font
					(size 1.27 1.27)
					(thickness 0.15)
				)
				(justify left bottom)
				(hide yes)
			)
		)
		(property "Val" "100k"
			(at 141.224 77.47 90)
			(effects
				(font
					(size 1.27 1.27)
					(thickness 0.15)
				)
				(justify right)
			)
		)
		(property "Tolerance" "1%"
			(at 149.86 58.42 0)
			(effects
				(font
					(size 1.27 1.27)
				)
				(justify left bottom)
				(hide yes)
			)
		)
		(pin "2"
		)
		(pin "1"
		)
		(instances
			(project "OCuLink to 10GbE adapter"
				(path ""
					(reference "R89")
					(unit 1)
				)
			)
		)
	)
	(symbol
		(lib_id "antmicropower:GND")
		(at 62.23 223.52 0)
		(mirror y)
		(unit 1)
		(exclude_from_sim no)
		(in_bom yes)
		(on_board yes)
		(dnp no)
		(property "Reference" "#PWR0102"
			(at 53.34 226.06 0)
			(effects
				(font
					(size 1.27 1.27)
					(thickness 0.15)
				)
				(justify left bottom)
				(hide yes)
			)
		)
		(property "Value" "GND"
			(at 62.23 227.33 0)
			(effects
				(font
					(size 1.27 1.27)
					(thickness 0.15)
				)
			)
		)
		(property "Footprint" ""
			(at 53.34 231.14 0)
			(effects
				(font
					(size 1.27 1.27)
					(thickness 0.15)
				)
				(justify left bottom)
				(hide yes)
			)
		)
		(property "Datasheet" ""
			(at 53.34 236.22 0)
			(effects
				(font
					(size 1.27 1.27)
					(thickness 0.15)
				)
				(justify left bottom)
				(hide yes)
			)
		)
		(property "Description" ""
			(at 62.23 223.52 0)
			(effects
				(font
					(size 1.27 1.27)
				)
				(hide yes)
			)
		)
		(property "Author" "Antmicro"
			(at 53.34 231.14 0)
			(effects
				(font
					(size 1.27 1.27)
					(thickness 0.15)
				)
				(justify left bottom)
				(hide yes)
			)
		)
		(property "License" "Apache-2.0"
			(at 53.34 233.68 0)
			(effects
				(font
					(size 1.27 1.27)
					(thickness 0.15)
				)
				(justify left bottom)
				(hide yes)
			)
		)
		(pin "1"
		)
		(instances
			(project "OCuLink to 10GbE adapter"
				(path ""
					(reference "#PWR0102")
					(unit 1)
				)
			)
		)
	)
	(symbol
		(lib_id "antmicroResistors0402:R_1k_0402")
		(at 149.86 243.84 90)
		(unit 1)
		(exclude_from_sim no)
		(in_bom yes)
		(on_board yes)
		(dnp no)
		(property "Reference" "R121"
			(at 151.384 240.03 90)
			(effects
				(font
					(size 1.27 1.27)
					(thickness 0.15)
				)
				(justify right)
			)
		)
		(property "Value" "R_1k_0402"
			(at 162.56 223.52 0)
			(effects
				(font
					(size 1.27 1.27)
					(thickness 0.15)
				)
				(justify left bottom)
				(hide yes)
			)
		)
		(property "Footprint" "antmicro-footprints:R_0402_1005Metric"
			(at 165.1 223.52 0)
			(effects
				(font
					(size 1.27 1.27)
					(thickness 0.15)
				)
				(justify left bottom)
				(hide yes)
			)
		)
		(property "Datasheet" "https://www.bourns.com/docs/product-datasheets/cr.pdf"
			(at 167.64 223.52 0)
			(effects
				(font
					(size 1.27 1.27)
					(thickness 0.15)
				)
				(justify left bottom)
				(hide yes)
			)
		)
		(property "Description" "SMD Chip Resistor, 1 kohm, ± 1%, 63 mW, 0402 [1005 Metric], Thick Film, General Purpose"
			(at 149.86 243.84 0)
			(effects
				(font
					(size 1.27 1.27)
				)
				(hide yes)
			)
		)
		(property "MPN" "CR0402-FX-1001GLF"
			(at 170.18 223.52 0)
			(effects
				(font
					(size 1.27 1.27)
					(thickness 0.15)
				)
				(justify left bottom)
				(hide yes)
			)
		)
		(property "Manufacturer" "Bourns"
			(at 172.72 223.52 0)
			(effects
				(font
					(size 1.27 1.27)
					(thickness 0.15)
				)
				(justify left bottom)
				(hide yes)
			)
		)
		(property "License" "Apache-2.0"
			(at 175.26 223.52 0)
			(effects
				(font
					(size 1.27 1.27)
					(thickness 0.15)
				)
				(justify left bottom)
				(hide yes)
			)
		)
		(property "Author" "Antmicro"
			(at 177.8 223.52 0)
			(effects
				(font
					(size 1.27 1.27)
					(thickness 0.15)
				)
				(justify left bottom)
				(hide yes)
			)
		)
		(property "Val" "1k"
			(at 151.384 242.57 90)
			(effects
				(font
					(size 1.27 1.27)
					(thickness 0.15)
				)
				(justify right)
			)
		)
		(property "Tolerance" "1%"
			(at 160.02 223.52 0)
			(effects
				(font
					(size 1.27 1.27)
				)
				(justify left bottom)
				(hide yes)
			)
		)
		(pin "1"
		)
		(pin "2"
		)
		(instances
			(project ""
				(path ""
					(reference "R121")
					(unit 1)
				)
			)
		)
	)
	(symbol
		(lib_id "antmicropower:GND")
		(at 67.31 195.58 0)
		(mirror y)
		(unit 1)
		(exclude_from_sim no)
		(in_bom yes)
		(on_board yes)
		(dnp no)
		(property "Reference" "#PWR0111"
			(at 58.42 198.12 0)
			(effects
				(font
					(size 1.27 1.27)
					(thickness 0.15)
				)
				(justify left bottom)
				(hide yes)
			)
		)
		(property "Value" "GND"
			(at 67.31 199.39 0)
			(effects
				(font
					(size 1.27 1.27)
					(thickness 0.15)
				)
			)
		)
		(property "Footprint" ""
			(at 58.42 203.2 0)
			(effects
				(font
					(size 1.27 1.27)
					(thickness 0.15)
				)
				(justify left bottom)
				(hide yes)
			)
		)
		(property "Datasheet" ""
			(at 58.42 208.28 0)
			(effects
				(font
					(size 1.27 1.27)
					(thickness 0.15)
				)
				(justify left bottom)
				(hide yes)
			)
		)
		(property "Description" ""
			(at 67.31 195.58 0)
			(effects
				(font
					(size 1.27 1.27)
				)
				(hide yes)
			)
		)
		(property "Author" "Antmicro"
			(at 58.42 203.2 0)
			(effects
				(font
					(size 1.27 1.27)
					(thickness 0.15)
				)
				(justify left bottom)
				(hide yes)
			)
		)
		(property "License" "Apache-2.0"
			(at 58.42 205.74 0)
			(effects
				(font
					(size 1.27 1.27)
					(thickness 0.15)
				)
				(justify left bottom)
				(hide yes)
			)
		)
		(pin "1"
		)
		(instances
			(project "OCuLink to 10GbE adapter"
				(path ""
					(reference "#PWR0111")
					(unit 1)
				)
			)
		)
	)
	(symbol
		(lib_id "antmicroResistors0402:R_10k_0402")
		(at 274.32 96.52 90)
		(unit 1)
		(exclude_from_sim no)
		(in_bom yes)
		(on_board yes)
		(dnp no)
		(property "Reference" "R94"
			(at 275.844 92.71 90)
			(effects
				(font
					(size 1.27 1.27)
					(thickness 0.15)
				)
				(justify right)
			)
		)
		(property "Value" "R_10k_0402"
			(at 287.02 76.2 0)
			(effects
				(font
					(size 1.27 1.27)
					(thickness 0.15)
				)
				(justify left bottom)
				(hide yes)
			)
		)
		(property "Footprint" "antmicro-footprints:R_0402_1005Metric"
			(at 289.56 76.2 0)
			(effects
				(font
					(size 1.27 1.27)
					(thickness 0.15)
				)
				(justify left bottom)
				(hide yes)
			)
		)
		(property "Datasheet" "https://www.bourns.com/docs/product-datasheets/cr.pdf"
			(at 292.1 76.2 0)
			(effects
				(font
					(size 1.27 1.27)
					(thickness 0.15)
				)
				(justify left bottom)
				(hide yes)
			)
		)
		(property "Description" "SMD Chip Resistor, 10 kohm, ± 1%, 62.5 mW, 0402 [1005 Metric], Thick Film, General Purpose"
			(at 274.32 96.52 0)
			(effects
				(font
					(size 1.27 1.27)
				)
				(hide yes)
			)
		)
		(property "MPN" "CR0402-FX-1002GLF"
			(at 294.64 76.2 0)
			(effects
				(font
					(size 1.27 1.27)
					(thickness 0.15)
				)
				(justify left bottom)
				(hide yes)
			)
		)
		(property "Manufacturer" "Bourns"
			(at 297.18 76.2 0)
			(effects
				(font
					(size 1.27 1.27)
					(thickness 0.15)
				)
				(justify left bottom)
				(hide yes)
			)
		)
		(property "License" "Apache-2.0"
			(at 299.72 76.2 0)
			(effects
				(font
					(size 1.27 1.27)
					(thickness 0.15)
				)
				(justify left bottom)
				(hide yes)
			)
		)
		(property "Author" "Antmicro"
			(at 302.26 76.2 0)
			(effects
				(font
					(size 1.27 1.27)
					(thickness 0.15)
				)
				(justify left bottom)
				(hide yes)
			)
		)
		(property "Val" "10k"
			(at 275.844 95.25 90)
			(effects
				(font
					(size 1.27 1.27)
					(thickness 0.15)
				)
				(justify right)
			)
		)
		(property "Tolerance" "1%"
			(at 284.48 76.2 0)
			(effects
				(font
					(size 1.27 1.27)
				)
				(justify left bottom)
				(hide yes)
			)
		)
		(pin "2"
		)
		(pin "1"
		)
		(instances
			(project "OCuLink to 10GbE adapter"
				(path ""
					(reference "R94")
					(unit 1)
				)
			)
		)
	)
	(symbol
		(lib_id "antmicropower:GND")
		(at 106.68 237.49 0)
		(mirror y)
		(unit 1)
		(exclude_from_sim no)
		(in_bom yes)
		(on_board yes)
		(dnp no)
		(property "Reference" "#PWR0103"
			(at 97.79 240.03 0)
			(effects
				(font
					(size 1.27 1.27)
					(thickness 0.15)
				)
				(justify left bottom)
				(hide yes)
			)
		)
		(property "Value" "GND"
			(at 106.68 241.3 0)
			(effects
				(font
					(size 1.27 1.27)
					(thickness 0.15)
				)
			)
		)
		(property "Footprint" ""
			(at 97.79 245.11 0)
			(effects
				(font
					(size 1.27 1.27)
					(thickness 0.15)
				)
				(justify left bottom)
				(hide yes)
			)
		)
		(property "Datasheet" ""
			(at 97.79 250.19 0)
			(effects
				(font
					(size 1.27 1.27)
					(thickness 0.15)
				)
				(justify left bottom)
				(hide yes)
			)
		)
		(property "Description" ""
			(at 106.68 237.49 0)
			(effects
				(font
					(size 1.27 1.27)
				)
				(hide yes)
			)
		)
		(property "Author" "Antmicro"
			(at 97.79 245.11 0)
			(effects
				(font
					(size 1.27 1.27)
					(thickness 0.15)
				)
				(justify left bottom)
				(hide yes)
			)
		)
		(property "License" "Apache-2.0"
			(at 97.79 247.65 0)
			(effects
				(font
					(size 1.27 1.27)
					(thickness 0.15)
				)
				(justify left bottom)
				(hide yes)
			)
		)
		(pin "1"
		)
		(instances
			(project "OCuLink to 10GbE adapter"
				(path ""
					(reference "#PWR0103")
					(unit 1)
				)
			)
		)
	)
	(symbol
		(lib_id "antmicropower:GND")
		(at 154.94 132.08 0)
		(unit 1)
		(exclude_from_sim no)
		(in_bom yes)
		(on_board yes)
		(dnp no)
		(property "Reference" "#PWR0273"
			(at 163.83 134.62 0)
			(effects
				(font
					(size 1.27 1.27)
					(thickness 0.15)
				)
				(justify left bottom)
				(hide yes)
			)
		)
		(property "Value" "GND"
			(at 154.94 135.89 0)
			(effects
				(font
					(size 1.27 1.27)
					(thickness 0.15)
				)
			)
		)
		(property "Footprint" ""
			(at 163.83 139.7 0)
			(effects
				(font
					(size 1.27 1.27)
					(thickness 0.15)
				)
				(justify left bottom)
				(hide yes)
			)
		)
		(property "Datasheet" ""
			(at 163.83 144.78 0)
			(effects
				(font
					(size 1.27 1.27)
					(thickness 0.15)
				)
				(justify left bottom)
				(hide yes)
			)
		)
		(property "Description" ""
			(at 154.94 132.08 0)
			(effects
				(font
					(size 1.27 1.27)
				)
				(hide yes)
			)
		)
		(property "Author" "Antmicro"
			(at 163.83 139.7 0)
			(effects
				(font
					(size 1.27 1.27)
					(thickness 0.15)
				)
				(justify left bottom)
				(hide yes)
			)
		)
		(property "License" "Apache-2.0"
			(at 163.83 142.24 0)
			(effects
				(font
					(size 1.27 1.27)
					(thickness 0.15)
				)
				(justify left bottom)
				(hide yes)
			)
		)
		(pin "1"
		)
		(instances
			(project "OCuLink to 10GbE adapter"
				(path ""
					(reference "#PWR0273")
					(unit 1)
				)
			)
		)
	)
	(symbol
		(lib_id "antmicroTestPoints:TP_0.75mm_SMD")
		(at 92.71 58.42 180)
		(unit 1)
		(exclude_from_sim no)
		(in_bom no)
		(on_board yes)
		(dnp no)
		(property "Reference" "TP4"
			(at 88.392 58.42 0)
			(effects
				(font
					(size 1.27 1.27)
					(thickness 0.15)
				)
				(justify left)
			)
		)
		(property "Value" "TP_0.75mm_SMD"
			(at 82.55 54.61 0)
			(effects
				(font
					(size 1.27 1.27)
					(thickness 0.15)
				)
				(justify left bottom)
				(hide yes)
			)
		)
		(property "Footprint" "antmicro-footprints:TP_SMD_0.75mm"
			(at 82.55 52.07 0)
			(effects
				(font
					(size 1.27 1.27)
					(thickness 0.15)
				)
				(justify left bottom)
				(hide yes)
			)
		)
		(property "Datasheet" ""
			(at 74.93 45.72 0)
			(effects
				(font
					(size 1.27 1.27)
					(thickness 0.15)
				)
				(justify left bottom)
				(hide yes)
			)
		)
		(property "Description" "SMT test point"
			(at 92.71 58.42 0)
			(effects
				(font
					(size 1.27 1.27)
				)
				(hide yes)
			)
		)
		(property "MPN" ""
			(at 81.915 46.99 0)
			(effects
				(font
					(size 1.27 1.27)
					(thickness 0.15)
				)
				(justify left bottom)
				(hide yes)
			)
		)
		(property "Manufacturer" ""
			(at 81.915 52.07 0)
			(effects
				(font
					(size 1.27 1.27)
					(thickness 0.15)
				)
				(justify left bottom)
				(hide yes)
			)
		)
		(property "Author" "Antmicro"
			(at 82.55 49.53 0)
			(effects
				(font
					(size 1.27 1.27)
					(thickness 0.15)
				)
				(justify left bottom)
				(hide yes)
			)
		)
		(property "License" "Apache-2.0"
			(at 82.55 46.99 0)
			(effects
				(font
					(size 1.27 1.27)
					(thickness 0.15)
				)
				(justify left bottom)
				(hide yes)
			)
		)
		(pin "1"
		)
		(instances
			(project "OCuLink to 10GbE adapter"
				(path ""
					(reference "TP4")
					(unit 1)
				)
			)
		)
	)
	(symbol
		(lib_id "antmicroResistors0402:R_0R_0402")
		(at 105.41 119.38 0)
		(unit 1)
		(exclude_from_sim no)
		(in_bom yes)
		(on_board yes)
		(dnp no)
		(property "Reference" "R104"
			(at 105.41 118.11 0)
			(effects
				(font
					(size 1.27 1.27)
					(thickness 0.15)
				)
				(justify right)
			)
		)
		(property "Value" "R_0R_0402"
			(at 125.73 132.08 0)
			(effects
				(font
					(size 1.27 1.27)
					(thickness 0.15)
				)
				(justify left bottom)
				(hide yes)
			)
		)
		(property "Footprint" "antmicro-footprints:R_0402_1005Metric"
			(at 125.73 134.62 0)
			(effects
				(font
					(size 1.27 1.27)
					(thickness 0.15)
				)
				(justify left bottom)
				(hide yes)
			)
		)
		(property "Datasheet" "https://industrial.panasonic.com/cdbs/www-data/pdf/RDA0000/AOA0000C301.pdf"
			(at 125.73 137.16 0)
			(effects
				(font
					(size 1.27 1.27)
					(thickness 0.15)
				)
				(justify left bottom)
				(hide yes)
			)
		)
		(property "Description" "SMD Chip Resistor, Jumper, 0 ohm, 100 mW, 0402 [1005 Metric], Thick Film, General Purpose"
			(at 105.41 119.38 0)
			(effects
				(font
					(size 1.27 1.27)
				)
				(hide yes)
			)
		)
		(property "MPN" "ERJ2GE0R00X"
			(at 125.73 139.7 0)
			(effects
				(font
					(size 1.27 1.27)
					(thickness 0.15)
				)
				(justify left bottom)
				(hide yes)
			)
		)
		(property "Manufacturer" "Panasonic"
			(at 125.73 142.24 0)
			(effects
				(font
					(size 1.27 1.27)
					(thickness 0.15)
				)
				(justify left bottom)
				(hide yes)
			)
		)
		(property "License" "Apache-2.0"
			(at 125.73 144.78 0)
			(effects
				(font
					(size 1.27 1.27)
					(thickness 0.15)
				)
				(justify left bottom)
				(hide yes)
			)
		)
		(property "Author" "Antmicro"
			(at 125.73 147.32 0)
			(effects
				(font
					(size 1.27 1.27)
					(thickness 0.15)
				)
				(justify left bottom)
				(hide yes)
			)
		)
		(property "Val" "0R"
			(at 110.49 118.11 0)
			(effects
				(font
					(size 1.27 1.27)
					(thickness 0.15)
				)
				(justify left)
			)
		)
		(property "Tolerance" "~"
			(at 125.73 129.54 0)
			(effects
				(font
					(size 1.27 1.27)
				)
				(justify left bottom)
				(hide yes)
			)
		)
		(property "Current" "1A"
			(at 125.73 149.86 0)
			(effects
				(font
					(size 1.27 1.27)
					(thickness 0.15)
				)
				(justify left bottom)
				(hide yes)
			)
		)
		(pin "1"
		)
		(pin "2"
		)
		(instances
			(project "OCuLink to 10GbE adapter"
				(path ""
					(reference "R104")
					(unit 1)
				)
			)
		)
	)
	(symbol
		(lib_id "antmicropower:+3V3")
		(at 110.49 38.1 0)
		(unit 1)
		(exclude_from_sim no)
		(in_bom yes)
		(on_board yes)
		(dnp no)
		(property "Reference" "#PWR0258"
			(at 125.73 38.1 0)
			(effects
				(font
					(size 1.27 1.27)
					(thickness 0.15)
				)
				(justify left bottom)
				(hide yes)
			)
		)
		(property "Value" "+3V3"
			(at 110.49 34.29 0)
			(effects
				(font
					(size 1.27 1.27)
					(thickness 0.15)
				)
			)
		)
		(property "Footprint" ""
			(at 125.73 45.72 0)
			(effects
				(font
					(size 1.27 1.27)
					(thickness 0.15)
				)
				(justify left bottom)
				(hide yes)
			)
		)
		(property "Datasheet" ""
			(at 125.73 48.26 0)
			(effects
				(font
					(size 1.27 1.27)
					(thickness 0.15)
				)
				(justify left bottom)
				(hide yes)
			)
		)
		(property "Description" ""
			(at 110.49 38.1 0)
			(effects
				(font
					(size 1.27 1.27)
				)
				(hide yes)
			)
		)
		(property "Author" "Antmicro"
			(at 125.73 40.64 0)
			(effects
				(font
					(size 1.27 1.27)
					(thickness 0.15)
				)
				(justify left bottom)
				(hide yes)
			)
		)
		(property "License" "Apache-2.0"
			(at 125.73 43.18 0)
			(effects
				(font
					(size 1.27 1.27)
					(thickness 0.15)
				)
				(justify left bottom)
				(hide yes)
			)
		)
		(pin "1"
		)
		(instances
			(project "OCuLink to 10GbE adapter"
				(path ""
					(reference "#PWR0258")
					(unit 1)
				)
			)
		)
	)
	(symbol
		(lib_id "antmicropower:GND")
		(at 55.88 237.49 0)
		(mirror y)
		(unit 1)
		(exclude_from_sim no)
		(in_bom yes)
		(on_board yes)
		(dnp no)
		(property "Reference" "#PWR0105"
			(at 46.99 240.03 0)
			(effects
				(font
					(size 1.27 1.27)
					(thickness 0.15)
				)
				(justify left bottom)
				(hide yes)
			)
		)
		(property "Value" "GND"
			(at 55.88 241.3 0)
			(effects
				(font
					(size 1.27 1.27)
					(thickness 0.15)
				)
			)
		)
		(property "Footprint" ""
			(at 46.99 245.11 0)
			(effects
				(font
					(size 1.27 1.27)
					(thickness 0.15)
				)
				(justify left bottom)
				(hide yes)
			)
		)
		(property "Datasheet" ""
			(at 46.99 250.19 0)
			(effects
				(font
					(size 1.27 1.27)
					(thickness 0.15)
				)
				(justify left bottom)
				(hide yes)
			)
		)
		(property "Description" ""
			(at 55.88 237.49 0)
			(effects
				(font
					(size 1.27 1.27)
				)
				(hide yes)
			)
		)
		(property "Author" "Antmicro"
			(at 46.99 245.11 0)
			(effects
				(font
					(size 1.27 1.27)
					(thickness 0.15)
				)
				(justify left bottom)
				(hide yes)
			)
		)
		(property "License" "Apache-2.0"
			(at 46.99 247.65 0)
			(effects
				(font
					(size 1.27 1.27)
					(thickness 0.15)
				)
				(justify left bottom)
				(hide yes)
			)
		)
		(pin "1"
		)
		(instances
			(project "OCuLink to 10GbE adapter"
				(path ""
					(reference "#PWR0105")
					(unit 1)
				)
			)
		)
	)
	(symbol
		(lib_id "antmicropower:GND")
		(at 148.59 81.28 0)
		(unit 1)
		(exclude_from_sim no)
		(in_bom yes)
		(on_board yes)
		(dnp no)
		(property "Reference" "#PWR0262"
			(at 157.48 83.82 0)
			(effects
				(font
					(size 1.27 1.27)
					(thickness 0.15)
				)
				(justify left bottom)
				(hide yes)
			)
		)
		(property "Value" "GND"
			(at 148.59 85.09 0)
			(effects
				(font
					(size 1.27 1.27)
					(thickness 0.15)
				)
			)
		)
		(property "Footprint" ""
			(at 157.48 88.9 0)
			(effects
				(font
					(size 1.27 1.27)
					(thickness 0.15)
				)
				(justify left bottom)
				(hide yes)
			)
		)
		(property "Datasheet" ""
			(at 157.48 93.98 0)
			(effects
				(font
					(size 1.27 1.27)
					(thickness 0.15)
				)
				(justify left bottom)
				(hide yes)
			)
		)
		(property "Description" ""
			(at 148.59 81.28 0)
			(effects
				(font
					(size 1.27 1.27)
				)
				(hide yes)
			)
		)
		(property "Author" "Antmicro"
			(at 157.48 88.9 0)
			(effects
				(font
					(size 1.27 1.27)
					(thickness 0.15)
				)
				(justify left bottom)
				(hide yes)
			)
		)
		(property "License" "Apache-2.0"
			(at 157.48 91.44 0)
			(effects
				(font
					(size 1.27 1.27)
					(thickness 0.15)
				)
				(justify left bottom)
				(hide yes)
			)
		)
		(pin "1"
		)
		(instances
			(project "OCuLink to 10GbE adapter"
				(path ""
					(reference "#PWR0262")
					(unit 1)
				)
			)
		)
	)
	(symbol
		(lib_id "antmicroResistors0402:R_0R_0402")
		(at 30.48 121.92 0)
		(unit 1)
		(exclude_from_sim no)
		(in_bom yes)
		(on_board yes)
		(dnp no)
		(property "Reference" "R105"
			(at 30.48 120.65 0)
			(effects
				(font
					(size 1.27 1.27)
					(thickness 0.15)
				)
				(justify right)
			)
		)
		(property "Value" "R_0R_0402"
			(at 50.8 134.62 0)
			(effects
				(font
					(size 1.27 1.27)
					(thickness 0.15)
				)
				(justify left bottom)
				(hide yes)
			)
		)
		(property "Footprint" "antmicro-footprints:R_0402_1005Metric"
			(at 50.8 137.16 0)
			(effects
				(font
					(size 1.27 1.27)
					(thickness 0.15)
				)
				(justify left bottom)
				(hide yes)
			)
		)
		(property "Datasheet" "https://industrial.panasonic.com/cdbs/www-data/pdf/RDA0000/AOA0000C301.pdf"
			(at 50.8 139.7 0)
			(effects
				(font
					(size 1.27 1.27)
					(thickness 0.15)
				)
				(justify left bottom)
				(hide yes)
			)
		)
		(property "Description" "SMD Chip Resistor, Jumper, 0 ohm, 100 mW, 0402 [1005 Metric], Thick Film, General Purpose"
			(at 30.48 121.92 0)
			(effects
				(font
					(size 1.27 1.27)
				)
				(hide yes)
			)
		)
		(property "MPN" "ERJ2GE0R00X"
			(at 50.8 142.24 0)
			(effects
				(font
					(size 1.27 1.27)
					(thickness 0.15)
				)
				(justify left bottom)
				(hide yes)
			)
		)
		(property "Manufacturer" "Panasonic"
			(at 50.8 144.78 0)
			(effects
				(font
					(size 1.27 1.27)
					(thickness 0.15)
				)
				(justify left bottom)
				(hide yes)
			)
		)
		(property "License" "Apache-2.0"
			(at 50.8 147.32 0)
			(effects
				(font
					(size 1.27 1.27)
					(thickness 0.15)
				)
				(justify left bottom)
				(hide yes)
			)
		)
		(property "Author" "Antmicro"
			(at 50.8 149.86 0)
			(effects
				(font
					(size 1.27 1.27)
					(thickness 0.15)
				)
				(justify left bottom)
				(hide yes)
			)
		)
		(property "Val" "0R"
			(at 35.56 120.65 0)
			(effects
				(font
					(size 1.27 1.27)
					(thickness 0.15)
				)
				(justify left)
			)
		)
		(property "Tolerance" "~"
			(at 50.8 132.08 0)
			(effects
				(font
					(size 1.27 1.27)
				)
				(justify left bottom)
				(hide yes)
			)
		)
		(property "Current" "1A"
			(at 50.8 152.4 0)
			(effects
				(font
					(size 1.27 1.27)
					(thickness 0.15)
				)
				(justify left bottom)
				(hide yes)
			)
		)
		(pin "1"
		)
		(pin "2"
		)
		(instances
			(project "OCuLink to 10GbE adapter"
				(path ""
					(reference "R105")
					(unit 1)
				)
			)
		)
	)
	(symbol
		(lib_id "antmicropower:+3V3")
		(at 274.32 86.36 0)
		(unit 1)
		(exclude_from_sim no)
		(in_bom yes)
		(on_board yes)
		(dnp no)
		(property "Reference" "#PWR0263"
			(at 289.56 86.36 0)
			(effects
				(font
					(size 1.27 1.27)
					(thickness 0.15)
				)
				(justify left bottom)
				(hide yes)
			)
		)
		(property "Value" "+3V3"
			(at 274.32 82.55 0)
			(effects
				(font
					(size 1.27 1.27)
					(thickness 0.15)
				)
			)
		)
		(property "Footprint" ""
			(at 289.56 93.98 0)
			(effects
				(font
					(size 1.27 1.27)
					(thickness 0.15)
				)
				(justify left bottom)
				(hide yes)
			)
		)
		(property "Datasheet" ""
			(at 289.56 96.52 0)
			(effects
				(font
					(size 1.27 1.27)
					(thickness 0.15)
				)
				(justify left bottom)
				(hide yes)
			)
		)
		(property "Description" ""
			(at 274.32 86.36 0)
			(effects
				(font
					(size 1.27 1.27)
				)
				(hide yes)
			)
		)
		(property "Author" "Antmicro"
			(at 289.56 88.9 0)
			(effects
				(font
					(size 1.27 1.27)
					(thickness 0.15)
				)
				(justify left bottom)
				(hide yes)
			)
		)
		(property "License" "Apache-2.0"
			(at 289.56 91.44 0)
			(effects
				(font
					(size 1.27 1.27)
					(thickness 0.15)
				)
				(justify left bottom)
				(hide yes)
			)
		)
		(pin "1"
		)
		(instances
			(project "OCuLink to 10GbE adapter"
				(path ""
					(reference "#PWR0263")
					(unit 1)
				)
			)
		)
	)
	(symbol
		(lib_id "antmicroCapacitors0402:C_5p6_0402")
		(at 137.16 172.72 90)
		(unit 1)
		(exclude_from_sim no)
		(in_bom yes)
		(on_board yes)
		(dnp no)
		(property "Reference" "C73"
			(at 139.192 168.91 90)
			(effects
				(font
					(size 1.27 1.27)
					(thickness 0.15)
				)
				(justify right)
			)
		)
		(property "Value" "C_5p6_0402"
			(at 147.32 152.4 0)
			(effects
				(font
					(size 1.27 1.27)
					(thickness 0.15)
				)
				(justify left bottom)
				(hide yes)
			)
		)
		(property "Footprint" "antmicro-footprints:C_0402_1005Metric"
			(at 149.86 152.4 0)
			(effects
				(font
					(size 1.27 1.27)
					(thickness 0.15)
				)
				(justify left bottom)
				(hide yes)
			)
		)
		(property "Datasheet" "https://www.mouser.com/datasheet/3/76/2/GCM1555C1H5R6BA16_01A.pdf"
			(at 152.4 152.4 0)
			(effects
				(font
					(size 1.27 1.27)
					(thickness 0.15)
				)
				(justify left bottom)
				(hide yes)
			)
		)
		(property "Description" "Multilayer Ceramic Capacitors MLCC - SMD/SMT 5.6 pF 50 VDC 0.1 pF 0402 C0G (NP0) AEC-Q200"
			(at 137.16 172.72 0)
			(effects
				(font
					(size 1.27 1.27)
				)
				(hide yes)
			)
		)
		(property "MPN" "GCM1555C1H5R6BA16D"
			(at 154.94 152.4 0)
			(effects
				(font
					(size 1.27 1.27)
					(thickness 0.15)
				)
				(justify left bottom)
				(hide yes)
			)
		)
		(property "Manufacturer" "Murata"
			(at 157.48 152.4 0)
			(effects
				(font
					(size 1.27 1.27)
					(thickness 0.15)
				)
				(justify left bottom)
				(hide yes)
			)
		)
		(property "License" "Apache-2.0"
			(at 160.02 152.4 0)
			(effects
				(font
					(size 1.27 1.27)
					(thickness 0.15)
				)
				(justify left bottom)
				(hide yes)
			)
		)
		(property "Author" "Antmicro"
			(at 162.56 152.4 0)
			(effects
				(font
					(size 1.27 1.27)
					(thickness 0.15)
				)
				(justify left bottom)
				(hide yes)
			)
		)
		(property "Val" "5p6"
			(at 139.192 171.45 90)
			(effects
				(font
					(size 1.27 1.27)
					(thickness 0.15)
				)
				(justify right)
			)
		)
		(property "Voltage" "50V"
			(at 165.1 152.4 0)
			(effects
				(font
					(size 1.27 1.27)
				)
				(justify left bottom)
				(hide yes)
			)
		)
		(property "Dielectric" "C0G"
			(at 167.64 152.4 0)
			(effects
				(font
					(size 1.27 1.27)
				)
				(justify left bottom)
				(hide yes)
			)
		)
		(pin "2"
		)
		(pin "1"
		)
		(instances
			(project "OCuLink to 10GbE adapter"
				(path ""
					(reference "C73")
					(unit 1)
				)
			)
		)
	)
	(symbol
		(lib_id "antmicroResistors0402:R_10k_0402")
		(at 110.49 104.14 90)
		(unit 1)
		(exclude_from_sim no)
		(in_bom yes)
		(on_board yes)
		(dnp no)
		(property "Reference" "R7"
			(at 111.76 100.33 90)
			(effects
				(font
					(size 1.27 1.27)
					(thickness 0.15)
				)
				(justify right)
			)
		)
		(property "Value" "R_10k_0402"
			(at 123.19 83.82 0)
			(effects
				(font
					(size 1.27 1.27)
					(thickness 0.15)
				)
				(justify left bottom)
				(hide yes)
			)
		)
		(property "Footprint" "antmicro-footprints:R_0402_1005Metric"
			(at 125.73 83.82 0)
			(effects
				(font
					(size 1.27 1.27)
					(thickness 0.15)
				)
				(justify left bottom)
				(hide yes)
			)
		)
		(property "Datasheet" "https://www.bourns.com/docs/product-datasheets/cr.pdf"
			(at 128.27 83.82 0)
			(effects
				(font
					(size 1.27 1.27)
					(thickness 0.15)
				)
				(justify left bottom)
				(hide yes)
			)
		)
		(property "Description" "SMD Chip Resistor, 10 kohm, ± 1%, 62.5 mW, 0402 [1005 Metric], Thick Film, General Purpose"
			(at 110.49 104.14 0)
			(effects
				(font
					(size 1.27 1.27)
				)
				(hide yes)
			)
		)
		(property "MPN" "CR0402-FX-1002GLF"
			(at 130.81 83.82 0)
			(effects
				(font
					(size 1.27 1.27)
					(thickness 0.15)
				)
				(justify left bottom)
				(hide yes)
			)
		)
		(property "Manufacturer" "Bourns"
			(at 133.35 83.82 0)
			(effects
				(font
					(size 1.27 1.27)
					(thickness 0.15)
				)
				(justify left bottom)
				(hide yes)
			)
		)
		(property "License" "Apache-2.0"
			(at 135.89 83.82 0)
			(effects
				(font
					(size 1.27 1.27)
					(thickness 0.15)
				)
				(justify left bottom)
				(hide yes)
			)
		)
		(property "Author" "Antmicro"
			(at 138.43 83.82 0)
			(effects
				(font
					(size 1.27 1.27)
					(thickness 0.15)
				)
				(justify left bottom)
				(hide yes)
			)
		)
		(property "Val" "10k"
			(at 111.76 102.87 90)
			(effects
				(font
					(size 1.27 1.27)
					(thickness 0.15)
				)
				(justify right)
			)
		)
		(property "Tolerance" "1%"
			(at 120.65 83.82 0)
			(effects
				(font
					(size 1.27 1.27)
				)
				(justify left bottom)
				(hide yes)
			)
		)
		(pin "2"
		)
		(pin "1"
		)
		(instances
			(project "OCuLink to 10GbE adapter"
				(path ""
					(reference "R7")
					(unit 1)
				)
			)
		)
	)
	(symbol
		(lib_id "antmicroTestPoints:TP_0.75mm_SMD")
		(at 92.71 55.88 180)
		(unit 1)
		(exclude_from_sim no)
		(in_bom no)
		(on_board yes)
		(dnp no)
		(property "Reference" "TP3"
			(at 88.392 55.88 0)
			(effects
				(font
					(size 1.27 1.27)
					(thickness 0.15)
				)
				(justify left)
			)
		)
		(property "Value" "TP_0.75mm_SMD"
			(at 82.55 52.07 0)
			(effects
				(font
					(size 1.27 1.27)
					(thickness 0.15)
				)
				(justify left bottom)
				(hide yes)
			)
		)
		(property "Footprint" "antmicro-footprints:TP_SMD_0.75mm"
			(at 82.55 49.53 0)
			(effects
				(font
					(size 1.27 1.27)
					(thickness 0.15)
				)
				(justify left bottom)
				(hide yes)
			)
		)
		(property "Datasheet" ""
			(at 74.93 43.18 0)
			(effects
				(font
					(size 1.27 1.27)
					(thickness 0.15)
				)
				(justify left bottom)
				(hide yes)
			)
		)
		(property "Description" "SMT test point"
			(at 92.71 55.88 0)
			(effects
				(font
					(size 1.27 1.27)
				)
				(hide yes)
			)
		)
		(property "MPN" ""
			(at 81.915 44.45 0)
			(effects
				(font
					(size 1.27 1.27)
					(thickness 0.15)
				)
				(justify left bottom)
				(hide yes)
			)
		)
		(property "Manufacturer" ""
			(at 81.915 49.53 0)
			(effects
				(font
					(size 1.27 1.27)
					(thickness 0.15)
				)
				(justify left bottom)
				(hide yes)
			)
		)
		(property "Author" "Antmicro"
			(at 82.55 46.99 0)
			(effects
				(font
					(size 1.27 1.27)
					(thickness 0.15)
				)
				(justify left bottom)
				(hide yes)
			)
		)
		(property "License" "Apache-2.0"
			(at 82.55 44.45 0)
			(effects
				(font
					(size 1.27 1.27)
					(thickness 0.15)
				)
				(justify left bottom)
				(hide yes)
			)
		)
		(pin "1"
		)
		(instances
			(project "OCuLink to 10GbE adapter"
				(path ""
					(reference "TP3")
					(unit 1)
				)
			)
		)
	)
	(symbol
		(lib_id "antmicroResistors0402:R_100R_0402")
		(at 135.89 129.54 90)
		(unit 1)
		(exclude_from_sim no)
		(in_bom no)
		(on_board yes)
		(dnp yes)
		(property "Reference" "R107"
			(at 137.414 125.73 90)
			(effects
				(font
					(size 1.27 1.27)
					(thickness 0.15)
				)
				(justify right)
			)
		)
		(property "Value" "R_100R_0402"
			(at 148.59 109.22 0)
			(effects
				(font
					(size 1.27 1.27)
					(thickness 0.15)
				)
				(justify left bottom)
				(hide yes)
			)
		)
		(property "Footprint" "antmicro-footprints:R_0402_1005Metric"
			(at 151.13 109.22 0)
			(effects
				(font
					(size 1.27 1.27)
					(thickness 0.15)
				)
				(justify left bottom)
				(hide yes)
			)
		)
		(property "Datasheet" "https://www.bourns.com/docs/product-datasheets/cr.pdf"
			(at 153.67 109.22 0)
			(effects
				(font
					(size 1.27 1.27)
					(thickness 0.15)
				)
				(justify left bottom)
				(hide yes)
			)
		)
		(property "Description" "SMD Chip Resistor, 100 ohm, ± 1%, 62.5 mW, 0402 [1005 Metric], Thick Film, General Purpose"
			(at 135.89 129.54 0)
			(effects
				(font
					(size 1.27 1.27)
				)
				(hide yes)
			)
		)
		(property "MPN" "CR0402-FX-1000GLF"
			(at 156.21 109.22 0)
			(effects
				(font
					(size 1.27 1.27)
					(thickness 0.15)
				)
				(justify left bottom)
				(hide yes)
			)
		)
		(property "Manufacturer" "Bourns"
			(at 158.75 109.22 0)
			(effects
				(font
					(size 1.27 1.27)
					(thickness 0.15)
				)
				(justify left bottom)
				(hide yes)
			)
		)
		(property "License" "Apache-2.0"
			(at 161.29 109.22 0)
			(effects
				(font
					(size 1.27 1.27)
					(thickness 0.15)
				)
				(justify left bottom)
				(hide yes)
			)
		)
		(property "Author" "Antmicro"
			(at 163.83 109.22 0)
			(effects
				(font
					(size 1.27 1.27)
					(thickness 0.15)
				)
				(justify left bottom)
				(hide yes)
			)
		)
		(property "Val" "100R"
			(at 137.414 128.27 90)
			(effects
				(font
					(size 1.27 1.27)
					(thickness 0.15)
				)
				(justify right)
			)
		)
		(property "Tolerance" "1%"
			(at 146.05 109.22 0)
			(effects
				(font
					(size 1.27 1.27)
				)
				(justify left bottom)
				(hide yes)
			)
		)
		(pin "2"
		)
		(pin "1"
		)
		(instances
			(project "OCuLink to 10GbE adapter"
				(path ""
					(reference "R107")
					(unit 1)
				)
			)
		)
	)
	(symbol
		(lib_id "antmicroResistors0402:R_10k_0402")
		(at 146.05 104.14 90)
		(unit 1)
		(exclude_from_sim no)
		(in_bom yes)
		(on_board yes)
		(dnp no)
		(property "Reference" "R99"
			(at 147.32 100.33 90)
			(effects
				(font
					(size 1.27 1.27)
					(thickness 0.15)
				)
				(justify right)
			)
		)
		(property "Value" "R_10k_0402"
			(at 158.75 83.82 0)
			(effects
				(font
					(size 1.27 1.27)
					(thickness 0.15)
				)
				(justify left bottom)
				(hide yes)
			)
		)
		(property "Footprint" "antmicro-footprints:R_0402_1005Metric"
			(at 161.29 83.82 0)
			(effects
				(font
					(size 1.27 1.27)
					(thickness 0.15)
				)
				(justify left bottom)
				(hide yes)
			)
		)
		(property "Datasheet" "https://www.bourns.com/docs/product-datasheets/cr.pdf"
			(at 163.83 83.82 0)
			(effects
				(font
					(size 1.27 1.27)
					(thickness 0.15)
				)
				(justify left bottom)
				(hide yes)
			)
		)
		(property "Description" "SMD Chip Resistor, 10 kohm, ± 1%, 62.5 mW, 0402 [1005 Metric], Thick Film, General Purpose"
			(at 146.05 104.14 0)
			(effects
				(font
					(size 1.27 1.27)
				)
				(hide yes)
			)
		)
		(property "MPN" "CR0402-FX-1002GLF"
			(at 166.37 83.82 0)
			(effects
				(font
					(size 1.27 1.27)
					(thickness 0.15)
				)
				(justify left bottom)
				(hide yes)
			)
		)
		(property "Manufacturer" "Bourns"
			(at 168.91 83.82 0)
			(effects
				(font
					(size 1.27 1.27)
					(thickness 0.15)
				)
				(justify left bottom)
				(hide yes)
			)
		)
		(property "License" "Apache-2.0"
			(at 171.45 83.82 0)
			(effects
				(font
					(size 1.27 1.27)
					(thickness 0.15)
				)
				(justify left bottom)
				(hide yes)
			)
		)
		(property "Author" "Antmicro"
			(at 173.99 83.82 0)
			(effects
				(font
					(size 1.27 1.27)
					(thickness 0.15)
				)
				(justify left bottom)
				(hide yes)
			)
		)
		(property "Val" "10k"
			(at 147.32 102.87 90)
			(effects
				(font
					(size 1.27 1.27)
					(thickness 0.15)
				)
				(justify right)
			)
		)
		(property "Tolerance" "1%"
			(at 156.21 83.82 0)
			(effects
				(font
					(size 1.27 1.27)
				)
				(justify left bottom)
				(hide yes)
			)
		)
		(pin "2"
		)
		(pin "1"
		)
		(instances
			(project "OCuLink to 10GbE adapter"
				(path ""
					(reference "R99")
					(unit 1)
				)
			)
		)
	)
	(symbol
		(lib_id "antmicroResistors0402:R_100k_0402")
		(at 119.38 48.26 90)
		(unit 1)
		(exclude_from_sim no)
		(in_bom yes)
		(on_board yes)
		(dnp no)
		(property "Reference" "R79"
			(at 120.904 44.45 90)
			(effects
				(font
					(size 1.27 1.27)
					(thickness 0.15)
				)
				(justify right)
			)
		)
		(property "Value" "R_100k_0402"
			(at 132.08 27.94 0)
			(effects
				(font
					(size 1.27 1.27)
					(thickness 0.15)
				)
				(justify left bottom)
				(hide yes)
			)
		)
		(property "Footprint" "antmicro-footprints:R_0402_1005Metric"
			(at 134.62 27.94 0)
			(effects
				(font
					(size 1.27 1.27)
					(thickness 0.15)
				)
				(justify left bottom)
				(hide yes)
			)
		)
		(property "Datasheet" "https://www.bourns.com/docs/product-datasheets/cr.pdf"
			(at 137.16 27.94 0)
			(effects
				(font
					(size 1.27 1.27)
					(thickness 0.15)
				)
				(justify left bottom)
				(hide yes)
			)
		)
		(property "Description" "SMD Chip Resistor, 100 kohm, ± 1%, 62.5 mW, 0402 [1005 Metric], Thick Film, General Purpose"
			(at 119.38 48.26 0)
			(effects
				(font
					(size 1.27 1.27)
				)
				(hide yes)
			)
		)
		(property "MPN" "CR0402-FX-1003GLF"
			(at 139.7 27.94 0)
			(effects
				(font
					(size 1.27 1.27)
					(thickness 0.15)
				)
				(justify left bottom)
				(hide yes)
			)
		)
		(property "Manufacturer" "Bourns"
			(at 142.24 27.94 0)
			(effects
				(font
					(size 1.27 1.27)
					(thickness 0.15)
				)
				(justify left bottom)
				(hide yes)
			)
		)
		(property "License" "Apache-2.0"
			(at 144.78 27.94 0)
			(effects
				(font
					(size 1.27 1.27)
					(thickness 0.15)
				)
				(justify left bottom)
				(hide yes)
			)
		)
		(property "Author" "Antmicro"
			(at 147.32 27.94 0)
			(effects
				(font
					(size 1.27 1.27)
					(thickness 0.15)
				)
				(justify left bottom)
				(hide yes)
			)
		)
		(property "Val" "100k"
			(at 120.904 46.99 90)
			(effects
				(font
					(size 1.27 1.27)
					(thickness 0.15)
				)
				(justify right)
			)
		)
		(property "Tolerance" "1%"
			(at 129.54 27.94 0)
			(effects
				(font
					(size 1.27 1.27)
				)
				(justify left bottom)
				(hide yes)
			)
		)
		(pin "2"
		)
		(pin "1"
		)
		(instances
			(project "OCuLink to 10GbE adapter"
				(path ""
					(reference "R79")
					(unit 1)
				)
			)
		)
	)
	(symbol
		(lib_id "antmicropower:+1V8")
		(at 172.72 175.26 0)
		(unit 1)
		(exclude_from_sim no)
		(in_bom yes)
		(on_board yes)
		(dnp no)
		(property "Reference" "#PWR0277"
			(at 187.96 177.8 0)
			(effects
				(font
					(size 1.27 1.27)
					(thickness 0.15)
				)
				(justify left bottom)
				(hide yes)
			)
		)
		(property "Value" "+1V88"
			(at 172.72 171.45 0)
			(effects
				(font
					(size 1.27 1.27)
					(thickness 0.15)
				)
			)
		)
		(property "Footprint" ""
			(at 187.96 182.88 0)
			(effects
				(font
					(size 1.27 1.27)
					(thickness 0.15)
				)
				(justify left bottom)
				(hide yes)
			)
		)
		(property "Datasheet" ""
			(at 187.96 185.42 0)
			(effects
				(font
					(size 1.27 1.27)
					(thickness 0.15)
				)
				(justify left bottom)
				(hide yes)
			)
		)
		(property "Description" ""
			(at 172.72 175.26 0)
			(effects
				(font
					(size 1.27 1.27)
				)
				(hide yes)
			)
		)
		(property "Author" "Antmicro"
			(at 187.96 180.34 0)
			(effects
				(font
					(size 1.27 1.27)
					(thickness 0.15)
				)
				(justify left bottom)
				(hide yes)
			)
		)
		(property "License" "Apache-2.0"
			(at 187.96 182.88 0)
			(effects
				(font
					(size 1.27 1.27)
					(thickness 0.15)
				)
				(justify left bottom)
				(hide yes)
			)
		)
		(pin "1"
		)
		(instances
			(project "OCuLink to 10GbE adapter"
				(path ""
					(reference "#PWR0277")
					(unit 1)
				)
			)
		)
	)
	(symbol
		(lib_id "antmicroResistors0402:R_22R_0402")
		(at 254 116.84 0)
		(unit 1)
		(exclude_from_sim no)
		(in_bom yes)
		(on_board yes)
		(dnp no)
		(property "Reference" "R102"
			(at 254.254 115.824 0)
			(effects
				(font
					(size 1.27 1.27)
					(thickness 0.15)
				)
				(justify right)
			)
		)
		(property "Value" "R_22R_0402"
			(at 274.32 129.54 0)
			(effects
				(font
					(size 1.27 1.27)
					(thickness 0.15)
				)
				(justify left bottom)
				(hide yes)
			)
		)
		(property "Footprint" "antmicro-footprints:R_0402_1005Metric"
			(at 274.32 132.08 0)
			(effects
				(font
					(size 1.27 1.27)
					(thickness 0.15)
				)
				(justify left bottom)
				(hide yes)
			)
		)
		(property "Datasheet" "https://www.bourns.com/docs/product-datasheets/cr.pdf"
			(at 274.32 134.62 0)
			(effects
				(font
					(size 1.27 1.27)
					(thickness 0.15)
				)
				(justify left bottom)
				(hide yes)
			)
		)
		(property "Description" "SMD Chip Resistor, 22 ohm, ± 1%, 62.5 mW, 0402 [1005 Metric], Thick Film, General Purpose"
			(at 254 116.84 0)
			(effects
				(font
					(size 1.27 1.27)
				)
				(hide yes)
			)
		)
		(property "MPN" "CR0402-FX-22R0GLF"
			(at 274.32 137.16 0)
			(effects
				(font
					(size 1.27 1.27)
					(thickness 0.15)
				)
				(justify left bottom)
				(hide yes)
			)
		)
		(property "Manufacturer" "Bourns"
			(at 274.32 139.7 0)
			(effects
				(font
					(size 1.27 1.27)
					(thickness 0.15)
				)
				(justify left bottom)
				(hide yes)
			)
		)
		(property "License" "Apache-2.0"
			(at 274.32 142.24 0)
			(effects
				(font
					(size 1.27 1.27)
					(thickness 0.15)
				)
				(justify left bottom)
				(hide yes)
			)
		)
		(property "Author" "Antmicro"
			(at 274.32 144.78 0)
			(effects
				(font
					(size 1.27 1.27)
					(thickness 0.15)
				)
				(justify left bottom)
				(hide yes)
			)
		)
		(property "Val" "22R"
			(at 259.08 115.57 0)
			(effects
				(font
					(size 1.27 1.27)
					(thickness 0.15)
				)
				(justify left)
			)
		)
		(property "Tolerance" "1%"
			(at 274.32 127 0)
			(effects
				(font
					(size 1.27 1.27)
				)
				(justify left bottom)
				(hide yes)
			)
		)
		(pin "2"
		)
		(pin "1"
		)
		(instances
			(project ""
				(path ""
					(reference "R102")
					(unit 1)
				)
			)
		)
	)
	(symbol
		(lib_id "antmicroResonators:Resonator_50MHz_XRCGE")
		(at 115.57 162.56 0)
		(unit 1)
		(exclude_from_sim no)
		(in_bom yes)
		(on_board yes)
		(dnp no)
		(property "Reference" "Y2"
			(at 119.888 151.638 0)
			(effects
				(font
					(size 1.27 1.27)
					(thickness 0.15)
				)
			)
		)
		(property "Value" "Resonator_50MHz_XRCGE"
			(at 138.43 170.18 0)
			(effects
				(font
					(size 1.27 1.27)
					(thickness 0.15)
				)
				(justify left bottom)
				(hide yes)
			)
		)
		(property "Footprint" "antmicro-footprints:Resonator_SMD_Murata_XRCGB_2x1.6x0.65mm"
			(at 138.43 172.72 0)
			(effects
				(font
					(size 1.27 1.27)
					(thickness 0.15)
				)
				(justify left bottom)
				(hide yes)
			)
		)
		(property "Datasheet" "https://www.murata.com/products/productdata/8813268205598/SPEC-XRCGE50M000F5A2AR0.pdf"
			(at 138.43 175.26 0)
			(effects
				(font
					(size 1.27 1.27)
					(thickness 0.15)
				)
				(justify left bottom)
				(hide yes)
			)
		)
		(property "Description" "Crystal, 50 MHz, 2mm x 1.6mm, 50 ppm, 4.7 pF, 50 ppm, XRCGE Series"
			(at 115.57 162.56 0)
			(effects
				(font
					(size 1.27 1.27)
				)
				(hide yes)
			)
		)
		(property "Manufacturer" "Murata"
			(at 138.43 187.96 0)
			(effects
				(font
					(size 1.27 1.27)
				)
				(justify left bottom)
				(hide yes)
			)
		)
		(property "MPN" "XRCGE50M000F5A2AR0"
			(at 119.888 154.178 0)
			(effects
				(font
					(size 1.27 1.27)
				)
			)
		)
		(property "Val" "50MHz"
			(at 119.888 156.718 0)
			(effects
				(font
					(size 1.27 1.27)
				)
			)
		)
		(property "CLoad" "4.7pF"
			(at 138.43 182.88 0)
			(effects
				(font
					(size 1.27 1.27)
				)
				(justify left bottom)
				(hide yes)
			)
		)
		(property "Author" "Antmicro"
			(at 138.43 177.8 0)
			(effects
				(font
					(size 1.27 1.27)
				)
				(justify left bottom)
				(hide yes)
			)
		)
		(property "License" "Apache-2.0"
			(at 138.43 180.34 0)
			(effects
				(font
					(size 1.27 1.27)
				)
				(justify left bottom)
				(hide yes)
			)
		)
		(pin "4"
		)
		(pin "2"
		)
		(pin "3"
		)
		(pin "1"
		)
		(instances
			(project "OCuLink to 10GbE adapter"
				(path ""
					(reference "Y2")
					(unit 1)
				)
			)
		)
	)
	(symbol
		(lib_id "antmicropower:GND")
		(at 124.46 132.08 0)
		(unit 1)
		(exclude_from_sim no)
		(in_bom yes)
		(on_board yes)
		(dnp no)
		(property "Reference" "#PWR0270"
			(at 133.35 134.62 0)
			(effects
				(font
					(size 1.27 1.27)
					(thickness 0.15)
				)
				(justify left bottom)
				(hide yes)
			)
		)
		(property "Value" "GND"
			(at 124.46 135.89 0)
			(effects
				(font
					(size 1.27 1.27)
					(thickness 0.15)
				)
			)
		)
		(property "Footprint" ""
			(at 133.35 139.7 0)
			(effects
				(font
					(size 1.27 1.27)
					(thickness 0.15)
				)
				(justify left bottom)
				(hide yes)
			)
		)
		(property "Datasheet" ""
			(at 133.35 144.78 0)
			(effects
				(font
					(size 1.27 1.27)
					(thickness 0.15)
				)
				(justify left bottom)
				(hide yes)
			)
		)
		(property "Description" ""
			(at 124.46 132.08 0)
			(effects
				(font
					(size 1.27 1.27)
				)
				(hide yes)
			)
		)
		(property "Author" "Antmicro"
			(at 133.35 139.7 0)
			(effects
				(font
					(size 1.27 1.27)
					(thickness 0.15)
				)
				(justify left bottom)
				(hide yes)
			)
		)
		(property "License" "Apache-2.0"
			(at 133.35 142.24 0)
			(effects
				(font
					(size 1.27 1.27)
					(thickness 0.15)
				)
				(justify left bottom)
				(hide yes)
			)
		)
		(pin "1"
		)
		(instances
			(project "OCuLink to 10GbE adapter"
				(path ""
					(reference "#PWR0270")
					(unit 1)
				)
			)
		)
	)
	(symbol
		(lib_id "antmicropower:GND")
		(at 149.86 246.38 0)
		(unit 1)
		(exclude_from_sim no)
		(in_bom yes)
		(on_board yes)
		(dnp no)
		(property "Reference" "#PWR0282"
			(at 158.75 248.92 0)
			(effects
				(font
					(size 1.27 1.27)
					(thickness 0.15)
				)
				(justify left bottom)
				(hide yes)
			)
		)
		(property "Value" "GND"
			(at 149.86 250.19 0)
			(effects
				(font
					(size 1.27 1.27)
					(thickness 0.15)
				)
			)
		)
		(property "Footprint" ""
			(at 158.75 254 0)
			(effects
				(font
					(size 1.27 1.27)
					(thickness 0.15)
				)
				(justify left bottom)
				(hide yes)
			)
		)
		(property "Datasheet" ""
			(at 158.75 259.08 0)
			(effects
				(font
					(size 1.27 1.27)
					(thickness 0.15)
				)
				(justify left bottom)
				(hide yes)
			)
		)
		(property "Description" ""
			(at 149.86 246.38 0)
			(effects
				(font
					(size 1.27 1.27)
				)
				(hide yes)
			)
		)
		(property "Author" "Antmicro"
			(at 158.75 254 0)
			(effects
				(font
					(size 1.27 1.27)
					(thickness 0.15)
				)
				(justify left bottom)
				(hide yes)
			)
		)
		(property "License" "Apache-2.0"
			(at 158.75 256.54 0)
			(effects
				(font
					(size 1.27 1.27)
					(thickness 0.15)
				)
				(justify left bottom)
				(hide yes)
			)
		)
		(pin "1"
		)
		(instances
			(project "OCuLink to 10GbE adapter"
				(path ""
					(reference "#PWR0282")
					(unit 1)
				)
			)
		)
	)
	(symbol
		(lib_id "antmicroResistors0402:R_100k_0402")
		(at 121.92 78.74 90)
		(unit 1)
		(exclude_from_sim no)
		(in_bom yes)
		(on_board yes)
		(dnp no)
		(property "Reference" "R87"
			(at 123.444 74.93 90)
			(effects
				(font
					(size 1.27 1.27)
					(thickness 0.15)
				)
				(justify right)
			)
		)
		(property "Value" "R_100k_0402"
			(at 134.62 58.42 0)
			(effects
				(font
					(size 1.27 1.27)
					(thickness 0.15)
				)
				(justify left bottom)
				(hide yes)
			)
		)
		(property "Footprint" "antmicro-footprints:R_0402_1005Metric"
			(at 137.16 58.42 0)
			(effects
				(font
					(size 1.27 1.27)
					(thickness 0.15)
				)
				(justify left bottom)
				(hide yes)
			)
		)
		(property "Datasheet" "https://www.bourns.com/docs/product-datasheets/cr.pdf"
			(at 139.7 58.42 0)
			(effects
				(font
					(size 1.27 1.27)
					(thickness 0.15)
				)
				(justify left bottom)
				(hide yes)
			)
		)
		(property "Description" "SMD Chip Resistor, 100 kohm, ± 1%, 62.5 mW, 0402 [1005 Metric], Thick Film, General Purpose"
			(at 121.92 78.74 0)
			(effects
				(font
					(size 1.27 1.27)
				)
				(hide yes)
			)
		)
		(property "MPN" "CR0402-FX-1003GLF"
			(at 142.24 58.42 0)
			(effects
				(font
					(size 1.27 1.27)
					(thickness 0.15)
				)
				(justify left bottom)
				(hide yes)
			)
		)
		(property "Manufacturer" "Bourns"
			(at 144.78 58.42 0)
			(effects
				(font
					(size 1.27 1.27)
					(thickness 0.15)
				)
				(justify left bottom)
				(hide yes)
			)
		)
		(property "License" "Apache-2.0"
			(at 147.32 58.42 0)
			(effects
				(font
					(size 1.27 1.27)
					(thickness 0.15)
				)
				(justify left bottom)
				(hide yes)
			)
		)
		(property "Author" "Antmicro"
			(at 149.86 58.42 0)
			(effects
				(font
					(size 1.27 1.27)
					(thickness 0.15)
				)
				(justify left bottom)
				(hide yes)
			)
		)
		(property "Val" "100k"
			(at 123.444 77.47 90)
			(effects
				(font
					(size 1.27 1.27)
					(thickness 0.15)
				)
				(justify right)
			)
		)
		(property "Tolerance" "1%"
			(at 132.08 58.42 0)
			(effects
				(font
					(size 1.27 1.27)
				)
				(justify left bottom)
				(hide yes)
			)
		)
		(pin "2"
		)
		(pin "1"
		)
		(instances
			(project "OCuLink to 10GbE adapter"
				(path ""
					(reference "R87")
					(unit 1)
				)
			)
		)
	)
	(symbol
		(lib_id "antmicropower:GND")
		(at 158.75 246.38 0)
		(unit 1)
		(exclude_from_sim no)
		(in_bom yes)
		(on_board yes)
		(dnp no)
		(property "Reference" "#PWR0283"
			(at 167.64 248.92 0)
			(effects
				(font
					(size 1.27 1.27)
					(thickness 0.15)
				)
				(justify left bottom)
				(hide yes)
			)
		)
		(property "Value" "GND"
			(at 158.75 250.19 0)
			(effects
				(font
					(size 1.27 1.27)
					(thickness 0.15)
				)
			)
		)
		(property "Footprint" ""
			(at 167.64 254 0)
			(effects
				(font
					(size 1.27 1.27)
					(thickness 0.15)
				)
				(justify left bottom)
				(hide yes)
			)
		)
		(property "Datasheet" ""
			(at 167.64 259.08 0)
			(effects
				(font
					(size 1.27 1.27)
					(thickness 0.15)
				)
				(justify left bottom)
				(hide yes)
			)
		)
		(property "Description" ""
			(at 158.75 246.38 0)
			(effects
				(font
					(size 1.27 1.27)
				)
				(hide yes)
			)
		)
		(property "Author" "Antmicro"
			(at 167.64 254 0)
			(effects
				(font
					(size 1.27 1.27)
					(thickness 0.15)
				)
				(justify left bottom)
				(hide yes)
			)
		)
		(property "License" "Apache-2.0"
			(at 167.64 256.54 0)
			(effects
				(font
					(size 1.27 1.27)
					(thickness 0.15)
				)
				(justify left bottom)
				(hide yes)
			)
		)
		(pin "1"
		)
		(instances
			(project "OCuLink to 10GbE adapter"
				(path ""
					(reference "#PWR0283")
					(unit 1)
				)
			)
		)
	)
	(symbol
		(lib_id "antmicroTestPoints:TP_0.75mm_SMD")
		(at 92.71 66.04 180)
		(unit 1)
		(exclude_from_sim no)
		(in_bom no)
		(on_board yes)
		(dnp no)
		(property "Reference" "TP7"
			(at 88.392 66.04 0)
			(effects
				(font
					(size 1.27 1.27)
					(thickness 0.15)
				)
				(justify left)
			)
		)
		(property "Value" "TP_0.75mm_SMD"
			(at 82.55 62.23 0)
			(effects
				(font
					(size 1.27 1.27)
					(thickness 0.15)
				)
				(justify left bottom)
				(hide yes)
			)
		)
		(property "Footprint" "antmicro-footprints:TP_SMD_0.75mm"
			(at 82.55 59.69 0)
			(effects
				(font
					(size 1.27 1.27)
					(thickness 0.15)
				)
				(justify left bottom)
				(hide yes)
			)
		)
		(property "Datasheet" ""
			(at 74.93 53.34 0)
			(effects
				(font
					(size 1.27 1.27)
					(thickness 0.15)
				)
				(justify left bottom)
				(hide yes)
			)
		)
		(property "Description" "SMT test point"
			(at 92.71 66.04 0)
			(effects
				(font
					(size 1.27 1.27)
				)
				(hide yes)
			)
		)
		(property "MPN" ""
			(at 81.915 54.61 0)
			(effects
				(font
					(size 1.27 1.27)
					(thickness 0.15)
				)
				(justify left bottom)
				(hide yes)
			)
		)
		(property "Manufacturer" ""
			(at 81.915 59.69 0)
			(effects
				(font
					(size 1.27 1.27)
					(thickness 0.15)
				)
				(justify left bottom)
				(hide yes)
			)
		)
		(property "Author" "Antmicro"
			(at 82.55 57.15 0)
			(effects
				(font
					(size 1.27 1.27)
					(thickness 0.15)
				)
				(justify left bottom)
				(hide yes)
			)
		)
		(property "License" "Apache-2.0"
			(at 82.55 54.61 0)
			(effects
				(font
					(size 1.27 1.27)
					(thickness 0.15)
				)
				(justify left bottom)
				(hide yes)
			)
		)
		(pin "1"
		)
		(instances
			(project "OCuLink to 10GbE adapter"
				(path ""
					(reference "TP7")
					(unit 1)
				)
			)
		)
	)
	(symbol
		(lib_id "antmicroTestPoints:TP_0.75mm_SMD")
		(at 170.18 233.68 180)
		(unit 1)
		(exclude_from_sim no)
		(in_bom no)
		(on_board yes)
		(dnp no)
		(property "Reference" "TP13"
			(at 165.862 233.68 0)
			(effects
				(font
					(size 1.27 1.27)
					(thickness 0.15)
				)
				(justify left)
			)
		)
		(property "Value" "TP_0.75mm_SMD"
			(at 160.02 229.87 0)
			(effects
				(font
					(size 1.27 1.27)
					(thickness 0.15)
				)
				(justify left bottom)
				(hide yes)
			)
		)
		(property "Footprint" "antmicro-footprints:TP_SMD_0.75mm"
			(at 160.02 227.33 0)
			(effects
				(font
					(size 1.27 1.27)
					(thickness 0.15)
				)
				(justify left bottom)
				(hide yes)
			)
		)
		(property "Datasheet" ""
			(at 152.4 220.98 0)
			(effects
				(font
					(size 1.27 1.27)
					(thickness 0.15)
				)
				(justify left bottom)
				(hide yes)
			)
		)
		(property "Description" "SMT test point"
			(at 170.18 233.68 0)
			(effects
				(font
					(size 1.27 1.27)
				)
				(hide yes)
			)
		)
		(property "MPN" ""
			(at 159.385 222.25 0)
			(effects
				(font
					(size 1.27 1.27)
					(thickness 0.15)
				)
				(justify left bottom)
				(hide yes)
			)
		)
		(property "Manufacturer" ""
			(at 159.385 227.33 0)
			(effects
				(font
					(size 1.27 1.27)
					(thickness 0.15)
				)
				(justify left bottom)
				(hide yes)
			)
		)
		(property "Author" "Antmicro"
			(at 160.02 224.79 0)
			(effects
				(font
					(size 1.27 1.27)
					(thickness 0.15)
				)
				(justify left bottom)
				(hide yes)
			)
		)
		(property "License" "Apache-2.0"
			(at 160.02 222.25 0)
			(effects
				(font
					(size 1.27 1.27)
					(thickness 0.15)
				)
				(justify left bottom)
				(hide yes)
			)
		)
		(pin "1"
		)
		(instances
			(project "OCuLink to 10GbE adapter"
				(path ""
					(reference "TP13")
					(unit 1)
				)
			)
		)
	)
	(symbol
		(lib_id "antmicroResistors0402:R_100k_0402")
		(at 110.49 48.26 90)
		(unit 1)
		(exclude_from_sim no)
		(in_bom yes)
		(on_board yes)
		(dnp no)
		(property "Reference" "R78"
			(at 112.014 44.45 90)
			(effects
				(font
					(size 1.27 1.27)
					(thickness 0.15)
				)
				(justify right)
			)
		)
		(property "Value" "R_100k_0402"
			(at 123.19 27.94 0)
			(effects
				(font
					(size 1.27 1.27)
					(thickness 0.15)
				)
				(justify left bottom)
				(hide yes)
			)
		)
		(property "Footprint" "antmicro-footprints:R_0402_1005Metric"
			(at 125.73 27.94 0)
			(effects
				(font
					(size 1.27 1.27)
					(thickness 0.15)
				)
				(justify left bottom)
				(hide yes)
			)
		)
		(property "Datasheet" "https://www.bourns.com/docs/product-datasheets/cr.pdf"
			(at 128.27 27.94 0)
			(effects
				(font
					(size 1.27 1.27)
					(thickness 0.15)
				)
				(justify left bottom)
				(hide yes)
			)
		)
		(property "Description" "SMD Chip Resistor, 100 kohm, ± 1%, 62.5 mW, 0402 [1005 Metric], Thick Film, General Purpose"
			(at 110.49 48.26 0)
			(effects
				(font
					(size 1.27 1.27)
				)
				(hide yes)
			)
		)
		(property "MPN" "CR0402-FX-1003GLF"
			(at 130.81 27.94 0)
			(effects
				(font
					(size 1.27 1.27)
					(thickness 0.15)
				)
				(justify left bottom)
				(hide yes)
			)
		)
		(property "Manufacturer" "Bourns"
			(at 133.35 27.94 0)
			(effects
				(font
					(size 1.27 1.27)
					(thickness 0.15)
				)
				(justify left bottom)
				(hide yes)
			)
		)
		(property "License" "Apache-2.0"
			(at 135.89 27.94 0)
			(effects
				(font
					(size 1.27 1.27)
					(thickness 0.15)
				)
				(justify left bottom)
				(hide yes)
			)
		)
		(property "Author" "Antmicro"
			(at 138.43 27.94 0)
			(effects
				(font
					(size 1.27 1.27)
					(thickness 0.15)
				)
				(justify left bottom)
				(hide yes)
			)
		)
		(property "Val" "100k"
			(at 112.014 46.99 90)
			(effects
				(font
					(size 1.27 1.27)
					(thickness 0.15)
				)
				(justify right)
			)
		)
		(property "Tolerance" "1%"
			(at 120.65 27.94 0)
			(effects
				(font
					(size 1.27 1.27)
				)
				(justify left bottom)
				(hide yes)
			)
		)
		(pin "2"
		)
		(pin "1"
		)
		(instances
			(project "OCuLink to 10GbE adapter"
				(path ""
					(reference "R78")
					(unit 1)
				)
			)
		)
	)
	(symbol
		(lib_id "antmicroResistors0402:R_1k_0402")
		(at 241.3 157.48 270)
		(mirror x)
		(unit 1)
		(exclude_from_sim no)
		(in_bom yes)
		(on_board yes)
		(dnp no)
		(property "Reference" "R111"
			(at 239.776 153.67 90)
			(effects
				(font
					(size 1.27 1.27)
					(thickness 0.15)
				)
				(justify right)
			)
		)
		(property "Value" "R_1k_0402"
			(at 228.6 137.16 0)
			(effects
				(font
					(size 1.27 1.27)
					(thickness 0.15)
				)
				(justify left bottom)
				(hide yes)
			)
		)
		(property "Footprint" "antmicro-footprints:R_0402_1005Metric"
			(at 226.06 137.16 0)
			(effects
				(font
					(size 1.27 1.27)
					(thickness 0.15)
				)
				(justify left bottom)
				(hide yes)
			)
		)
		(property "Datasheet" "https://www.bourns.com/docs/product-datasheets/cr.pdf"
			(at 223.52 137.16 0)
			(effects
				(font
					(size 1.27 1.27)
					(thickness 0.15)
				)
				(justify left bottom)
				(hide yes)
			)
		)
		(property "Description" "SMD Chip Resistor, 1 kohm, ± 1%, 63 mW, 0402 [1005 Metric], Thick Film, General Purpose"
			(at 241.3 157.48 0)
			(effects
				(font
					(size 1.27 1.27)
				)
				(hide yes)
			)
		)
		(property "MPN" "CR0402-FX-1001GLF"
			(at 220.98 137.16 0)
			(effects
				(font
					(size 1.27 1.27)
					(thickness 0.15)
				)
				(justify left bottom)
				(hide yes)
			)
		)
		(property "Manufacturer" "Bourns"
			(at 218.44 137.16 0)
			(effects
				(font
					(size 1.27 1.27)
					(thickness 0.15)
				)
				(justify left bottom)
				(hide yes)
			)
		)
		(property "License" "Apache-2.0"
			(at 215.9 137.16 0)
			(effects
				(font
					(size 1.27 1.27)
					(thickness 0.15)
				)
				(justify left bottom)
				(hide yes)
			)
		)
		(property "Author" "Antmicro"
			(at 213.36 137.16 0)
			(effects
				(font
					(size 1.27 1.27)
					(thickness 0.15)
				)
				(justify left bottom)
				(hide yes)
			)
		)
		(property "Val" "1k"
			(at 239.776 156.21 90)
			(effects
				(font
					(size 1.27 1.27)
					(thickness 0.15)
				)
				(justify right)
			)
		)
		(property "Tolerance" "1%"
			(at 231.14 137.16 0)
			(effects
				(font
					(size 1.27 1.27)
				)
				(justify left bottom)
				(hide yes)
			)
		)
		(pin "2"
		)
		(pin "1"
		)
		(instances
			(project "OCuLink to 10GbE adapter"
				(path ""
					(reference "R111")
					(unit 1)
				)
			)
		)
	)
	(symbol
		(lib_id "antmicroResistors0402:R_100k_0402")
		(at 146.05 48.26 90)
		(unit 1)
		(exclude_from_sim no)
		(in_bom no)
		(on_board yes)
		(dnp yes)
		(property "Reference" "R82"
			(at 147.574 44.45 90)
			(effects
				(font
					(size 1.27 1.27)
					(thickness 0.15)
				)
				(justify right)
			)
		)
		(property "Value" "R_100k_0402"
			(at 158.75 27.94 0)
			(effects
				(font
					(size 1.27 1.27)
					(thickness 0.15)
				)
				(justify left bottom)
				(hide yes)
			)
		)
		(property "Footprint" "antmicro-footprints:R_0402_1005Metric"
			(at 161.29 27.94 0)
			(effects
				(font
					(size 1.27 1.27)
					(thickness 0.15)
				)
				(justify left bottom)
				(hide yes)
			)
		)
		(property "Datasheet" "https://www.bourns.com/docs/product-datasheets/cr.pdf"
			(at 163.83 27.94 0)
			(effects
				(font
					(size 1.27 1.27)
					(thickness 0.15)
				)
				(justify left bottom)
				(hide yes)
			)
		)
		(property "Description" "SMD Chip Resistor, 100 kohm, ± 1%, 62.5 mW, 0402 [1005 Metric], Thick Film, General Purpose"
			(at 146.05 48.26 0)
			(effects
				(font
					(size 1.27 1.27)
				)
				(hide yes)
			)
		)
		(property "MPN" "CR0402-FX-1003GLF"
			(at 166.37 27.94 0)
			(effects
				(font
					(size 1.27 1.27)
					(thickness 0.15)
				)
				(justify left bottom)
				(hide yes)
			)
		)
		(property "Manufacturer" "Bourns"
			(at 168.91 27.94 0)
			(effects
				(font
					(size 1.27 1.27)
					(thickness 0.15)
				)
				(justify left bottom)
				(hide yes)
			)
		)
		(property "License" "Apache-2.0"
			(at 171.45 27.94 0)
			(effects
				(font
					(size 1.27 1.27)
					(thickness 0.15)
				)
				(justify left bottom)
				(hide yes)
			)
		)
		(property "Author" "Antmicro"
			(at 173.99 27.94 0)
			(effects
				(font
					(size 1.27 1.27)
					(thickness 0.15)
				)
				(justify left bottom)
				(hide yes)
			)
		)
		(property "Val" "100k"
			(at 147.574 46.99 90)
			(effects
				(font
					(size 1.27 1.27)
					(thickness 0.15)
				)
				(justify right)
			)
		)
		(property "Tolerance" "1%"
			(at 156.21 27.94 0)
			(effects
				(font
					(size 1.27 1.27)
				)
				(justify left bottom)
				(hide yes)
			)
		)
		(pin "2"
		)
		(pin "1"
		)
		(instances
			(project "OCuLink to 10GbE adapter"
				(path ""
					(reference "R82")
					(unit 1)
				)
			)
		)
	)
	(symbol
		(lib_id "antmicropower:+1V8")
		(at 97.79 168.91 0)
		(mirror y)
		(unit 1)
		(exclude_from_sim no)
		(in_bom yes)
		(on_board yes)
		(dnp no)
		(property "Reference" "#PWR0106"
			(at 82.55 171.45 0)
			(effects
				(font
					(size 1.27 1.27)
					(thickness 0.15)
				)
				(justify left bottom)
				(hide yes)
			)
		)
		(property "Value" "+1V88"
			(at 97.79 165.1 0)
			(effects
				(font
					(size 1.27 1.27)
					(thickness 0.15)
				)
			)
		)
		(property "Footprint" ""
			(at 82.55 176.53 0)
			(effects
				(font
					(size 1.27 1.27)
					(thickness 0.15)
				)
				(justify left bottom)
				(hide yes)
			)
		)
		(property "Datasheet" ""
			(at 82.55 179.07 0)
			(effects
				(font
					(size 1.27 1.27)
					(thickness 0.15)
				)
				(justify left bottom)
				(hide yes)
			)
		)
		(property "Description" ""
			(at 97.79 168.91 0)
			(effects
				(font
					(size 1.27 1.27)
				)
				(hide yes)
			)
		)
		(property "Author" "Antmicro"
			(at 82.55 173.99 0)
			(effects
				(font
					(size 1.27 1.27)
					(thickness 0.15)
				)
				(justify left bottom)
				(hide yes)
			)
		)
		(property "License" "Apache-2.0"
			(at 82.55 176.53 0)
			(effects
				(font
					(size 1.27 1.27)
					(thickness 0.15)
				)
				(justify left bottom)
				(hide yes)
			)
		)
		(pin "1"
		)
		(instances
			(project "OCuLink to 10GbE adapter"
				(path ""
					(reference "#PWR0106")
					(unit 1)
				)
			)
		)
	)
	(symbol
		(lib_id "antmicroResistors0402:R_2k_0402")
		(at 106.68 220.98 90)
		(unit 1)
		(exclude_from_sim no)
		(in_bom yes)
		(on_board yes)
		(dnp no)
		(property "Reference" "R149"
			(at 107.95 217.17 90)
			(effects
				(font
					(size 1.27 1.27)
					(thickness 0.15)
				)
				(justify right)
			)
		)
		(property "Value" "R_2k_0402"
			(at 119.38 200.66 0)
			(effects
				(font
					(size 1.27 1.27)
					(thickness 0.15)
				)
				(justify left bottom)
				(hide yes)
			)
		)
		(property "Footprint" "antmicro-footprints:R_0402_1005Metric"
			(at 121.92 200.66 0)
			(effects
				(font
					(size 1.27 1.27)
					(thickness 0.15)
				)
				(justify left bottom)
				(hide yes)
			)
		)
		(property "Datasheet" "https://www.bourns.com/docs/product-datasheets/cr.pdf"
			(at 124.46 200.66 0)
			(effects
				(font
					(size 1.27 1.27)
					(thickness 0.15)
				)
				(justify left bottom)
				(hide yes)
			)
		)
		(property "Description" "SMD Chip Resistor, 2 kohm, ± 1%, 62.5 mW, 0402 [1005 Metric], Thick Film, General Purpose"
			(at 137.16 200.66 0)
			(effects
				(font
					(size 1.27 1.27)
				)
				(justify left bottom)
				(hide yes)
			)
		)
		(property "MPN" "CR0402-FX-2001GLF"
			(at 127 200.66 0)
			(effects
				(font
					(size 1.27 1.27)
					(thickness 0.15)
				)
				(justify left bottom)
				(hide yes)
			)
		)
		(property "Manufacturer" "Bourns"
			(at 129.54 200.66 0)
			(effects
				(font
					(size 1.27 1.27)
					(thickness 0.15)
				)
				(justify left bottom)
				(hide yes)
			)
		)
		(property "License" "Apache-2.0"
			(at 132.08 200.66 0)
			(effects
				(font
					(size 1.27 1.27)
					(thickness 0.15)
				)
				(justify left bottom)
				(hide yes)
			)
		)
		(property "Author" "Antmicro"
			(at 134.62 200.66 0)
			(effects
				(font
					(size 1.27 1.27)
					(thickness 0.15)
				)
				(justify left bottom)
				(hide yes)
			)
		)
		(property "Val" "2k"
			(at 107.95 219.71 90)
			(effects
				(font
					(size 1.27 1.27)
					(thickness 0.15)
				)
				(justify right)
			)
		)
		(property "Tolerance" "1%"
			(at 116.84 200.66 0)
			(effects
				(font
					(size 1.27 1.27)
				)
				(justify left bottom)
				(hide yes)
			)
		)
		(pin "2"
		)
		(pin "1"
		)
		(instances
			(project "oculink-to-10gbe-adapter"
				(path ""
					(reference "R149")
					(unit 1)
				)
			)
		)
	)
	(symbol
		(lib_id "antmicroTestPoints:TP_0.75mm_SMD")
		(at 92.71 63.5 180)
		(unit 1)
		(exclude_from_sim no)
		(in_bom no)
		(on_board yes)
		(dnp no)
		(property "Reference" "TP6"
			(at 88.392 63.5 0)
			(effects
				(font
					(size 1.27 1.27)
					(thickness 0.15)
				)
				(justify left)
			)
		)
		(property "Value" "TP_0.75mm_SMD"
			(at 82.55 59.69 0)
			(effects
				(font
					(size 1.27 1.27)
					(thickness 0.15)
				)
				(justify left bottom)
				(hide yes)
			)
		)
		(property "Footprint" "antmicro-footprints:TP_SMD_0.75mm"
			(at 82.55 57.15 0)
			(effects
				(font
					(size 1.27 1.27)
					(thickness 0.15)
				)
				(justify left bottom)
				(hide yes)
			)
		)
		(property "Datasheet" ""
			(at 74.93 50.8 0)
			(effects
				(font
					(size 1.27 1.27)
					(thickness 0.15)
				)
				(justify left bottom)
				(hide yes)
			)
		)
		(property "Description" "SMT test point"
			(at 92.71 63.5 0)
			(effects
				(font
					(size 1.27 1.27)
				)
				(hide yes)
			)
		)
		(property "MPN" ""
			(at 81.915 52.07 0)
			(effects
				(font
					(size 1.27 1.27)
					(thickness 0.15)
				)
				(justify left bottom)
				(hide yes)
			)
		)
		(property "Manufacturer" ""
			(at 81.915 57.15 0)
			(effects
				(font
					(size 1.27 1.27)
					(thickness 0.15)
				)
				(justify left bottom)
				(hide yes)
			)
		)
		(property "Author" "Antmicro"
			(at 82.55 54.61 0)
			(effects
				(font
					(size 1.27 1.27)
					(thickness 0.15)
				)
				(justify left bottom)
				(hide yes)
			)
		)
		(property "License" "Apache-2.0"
			(at 82.55 52.07 0)
			(effects
				(font
					(size 1.27 1.27)
					(thickness 0.15)
				)
				(justify left bottom)
				(hide yes)
			)
		)
		(pin "1"
		)
		(instances
			(project "OCuLink to 10GbE adapter"
				(path ""
					(reference "TP6")
					(unit 1)
				)
			)
		)
	)
	(symbol
		(lib_id "antmicroLogicTranslatorsLevelShifters:NTS0102_TSSOP")
		(at 90.17 227.33 0)
		(mirror y)
		(unit 1)
		(exclude_from_sim no)
		(in_bom yes)
		(on_board yes)
		(dnp no)
		(fields_autoplaced yes)
		(property "Reference" "U7"
			(at 80.01 219.71 0)
			(effects
				(font
					(size 1.27 1.27)
					(thickness 0.15)
				)
			)
		)
		(property "Value" "NTS0102_TSSOP"
			(at 54.61 233.68 0)
			(effects
				(font
					(size 1.27 1.27)
					(thickness 0.15)
				)
				(justify left bottom)
				(hide yes)
			)
		)
		(property "Footprint" "antmicro-footprints:TSSOP-8_3x3mm_P0.65mm"
			(at 54.61 236.22 0)
			(effects
				(font
					(size 1.27 1.27)
					(thickness 0.15)
				)
				(justify left bottom)
				(hide yes)
			)
		)
		(property "Datasheet" "https://www.mouser.com/datasheet/2/302/NTS0102-1127324.pdf"
			(at 54.61 238.76 0)
			(effects
				(font
					(size 1.27 1.27)
					(thickness 0.15)
				)
				(justify left bottom)
				(hide yes)
			)
		)
		(property "Description" "Transceiver, 1.65 V to 3.6 V, TSSOP-8"
			(at 90.17 227.33 0)
			(effects
				(font
					(size 1.27 1.27)
				)
				(hide yes)
			)
		)
		(property "MPN" "NTS0102DP"
			(at 80.01 222.25 0)
			(effects
				(font
					(size 1.27 1.27)
					(thickness 0.15)
				)
			)
		)
		(property "Manufacturer" "NXP"
			(at 54.61 243.84 0)
			(effects
				(font
					(size 1.27 1.27)
					(thickness 0.15)
				)
				(justify left bottom)
				(hide yes)
			)
		)
		(property "Author" "Antmicro"
			(at 54.61 246.38 0)
			(effects
				(font
					(size 1.27 1.27)
					(thickness 0.15)
				)
				(justify left bottom)
				(hide yes)
			)
		)
		(property "License" "Apache-2.0"
			(at 54.61 248.92 0)
			(effects
				(font
					(size 1.27 1.27)
					(thickness 0.15)
				)
				(justify left bottom)
				(hide yes)
			)
		)
		(pin "5"
		)
		(pin "3"
		)
		(pin "1"
		)
		(pin "6"
		)
		(pin "7"
		)
		(pin "4"
		)
		(pin "2"
		)
		(pin "8"
		)
		(instances
			(project "OCuLink to 10GbE adapter"
				(path ""
					(reference "U7")
					(unit 1)
				)
			)
		)
	)
	(symbol
		(lib_id "antmicropower:GND")
		(at 114.3 132.08 0)
		(unit 1)
		(exclude_from_sim no)
		(in_bom yes)
		(on_board yes)
		(dnp no)
		(property "Reference" "#PWR0269"
			(at 123.19 134.62 0)
			(effects
				(font
					(size 1.27 1.27)
					(thickness 0.15)
				)
				(justify left bottom)
				(hide yes)
			)
		)
		(property "Value" "GND"
			(at 114.3 135.89 0)
			(effects
				(font
					(size 1.27 1.27)
					(thickness 0.15)
				)
			)
		)
		(property "Footprint" ""
			(at 123.19 139.7 0)
			(effects
				(font
					(size 1.27 1.27)
					(thickness 0.15)
				)
				(justify left bottom)
				(hide yes)
			)
		)
		(property "Datasheet" ""
			(at 123.19 144.78 0)
			(effects
				(font
					(size 1.27 1.27)
					(thickness 0.15)
				)
				(justify left bottom)
				(hide yes)
			)
		)
		(property "Description" ""
			(at 114.3 132.08 0)
			(effects
				(font
					(size 1.27 1.27)
				)
				(hide yes)
			)
		)
		(property "Author" "Antmicro"
			(at 123.19 139.7 0)
			(effects
				(font
					(size 1.27 1.27)
					(thickness 0.15)
				)
				(justify left bottom)
				(hide yes)
			)
		)
		(property "License" "Apache-2.0"
			(at 123.19 142.24 0)
			(effects
				(font
					(size 1.27 1.27)
					(thickness 0.15)
				)
				(justify left bottom)
				(hide yes)
			)
		)
		(pin "1"
		)
		(instances
			(project "OCuLink to 10GbE adapter"
				(path ""
					(reference "#PWR0269")
					(unit 1)
				)
			)
		)
	)
	(symbol
		(lib_id "antmicroResistors0402:R_22R_0402")
		(at 153.67 71.12 0)
		(unit 1)
		(exclude_from_sim no)
		(in_bom yes)
		(on_board yes)
		(dnp no)
		(property "Reference" "R86"
			(at 153.67 69.85 0)
			(effects
				(font
					(size 1.27 1.27)
					(thickness 0.15)
				)
				(justify right)
			)
		)
		(property "Value" "R_22R_0402"
			(at 173.99 83.82 0)
			(effects
				(font
					(size 1.27 1.27)
					(thickness 0.15)
				)
				(justify left bottom)
				(hide yes)
			)
		)
		(property "Footprint" "antmicro-footprints:R_0402_1005Metric"
			(at 173.99 86.36 0)
			(effects
				(font
					(size 1.27 1.27)
					(thickness 0.15)
				)
				(justify left bottom)
				(hide yes)
			)
		)
		(property "Datasheet" "https://www.bourns.com/docs/product-datasheets/cr.pdf"
			(at 173.99 88.9 0)
			(effects
				(font
					(size 1.27 1.27)
					(thickness 0.15)
				)
				(justify left bottom)
				(hide yes)
			)
		)
		(property "Description" "SMD Chip Resistor, 22 ohm, ± 1%, 62.5 mW, 0402 [1005 Metric], Thick Film, General Purpose"
			(at 153.67 71.12 0)
			(effects
				(font
					(size 1.27 1.27)
				)
				(hide yes)
			)
		)
		(property "MPN" "CR0402-FX-22R0GLF"
			(at 173.99 91.44 0)
			(effects
				(font
					(size 1.27 1.27)
					(thickness 0.15)
				)
				(justify left bottom)
				(hide yes)
			)
		)
		(property "Manufacturer" "Bourns"
			(at 173.99 93.98 0)
			(effects
				(font
					(size 1.27 1.27)
					(thickness 0.15)
				)
				(justify left bottom)
				(hide yes)
			)
		)
		(property "License" "Apache-2.0"
			(at 173.99 96.52 0)
			(effects
				(font
					(size 1.27 1.27)
					(thickness 0.15)
				)
				(justify left bottom)
				(hide yes)
			)
		)
		(property "Author" "Antmicro"
			(at 173.99 99.06 0)
			(effects
				(font
					(size 1.27 1.27)
					(thickness 0.15)
				)
				(justify left bottom)
				(hide yes)
			)
		)
		(property "Val" "22R"
			(at 158.75 69.85 0)
			(effects
				(font
					(size 1.27 1.27)
					(thickness 0.15)
				)
				(justify left)
			)
		)
		(property "Tolerance" "1%"
			(at 173.99 81.28 0)
			(effects
				(font
					(size 1.27 1.27)
				)
				(justify left bottom)
				(hide yes)
			)
		)
		(pin "2"
		)
		(pin "1"
		)
		(instances
			(project "OCuLink to 10GbE adapter"
				(path ""
					(reference "R86")
					(unit 1)
				)
			)
		)
	)
	(symbol
		(lib_id "antmicropower:GND")
		(at 132.08 246.38 0)
		(unit 1)
		(exclude_from_sim no)
		(in_bom yes)
		(on_board yes)
		(dnp no)
		(property "Reference" "#PWR0280"
			(at 140.97 248.92 0)
			(effects
				(font
					(size 1.27 1.27)
					(thickness 0.15)
				)
				(justify left bottom)
				(hide yes)
			)
		)
		(property "Value" "GND"
			(at 132.08 250.19 0)
			(effects
				(font
					(size 1.27 1.27)
					(thickness 0.15)
				)
			)
		)
		(property "Footprint" ""
			(at 140.97 254 0)
			(effects
				(font
					(size 1.27 1.27)
					(thickness 0.15)
				)
				(justify left bottom)
				(hide yes)
			)
		)
		(property "Datasheet" ""
			(at 140.97 259.08 0)
			(effects
				(font
					(size 1.27 1.27)
					(thickness 0.15)
				)
				(justify left bottom)
				(hide yes)
			)
		)
		(property "Description" ""
			(at 132.08 246.38 0)
			(effects
				(font
					(size 1.27 1.27)
				)
				(hide yes)
			)
		)
		(property "Author" "Antmicro"
			(at 140.97 254 0)
			(effects
				(font
					(size 1.27 1.27)
					(thickness 0.15)
				)
				(justify left bottom)
				(hide yes)
			)
		)
		(property "License" "Apache-2.0"
			(at 140.97 256.54 0)
			(effects
				(font
					(size 1.27 1.27)
					(thickness 0.15)
				)
				(justify left bottom)
				(hide yes)
			)
		)
		(pin "1"
		)
		(instances
			(project "OCuLink to 10GbE adapter"
				(path ""
					(reference "#PWR0280")
					(unit 1)
				)
			)
		)
	)
	(symbol
		(lib_id "antmicroResistors0402:R_22R_0402")
		(at 153.67 58.42 0)
		(unit 1)
		(exclude_from_sim no)
		(in_bom yes)
		(on_board yes)
		(dnp no)
		(property "Reference" "R84"
			(at 153.67 57.15 0)
			(effects
				(font
					(size 1.27 1.27)
					(thickness 0.15)
				)
				(justify right)
			)
		)
		(property "Value" "R_22R_0402"
			(at 173.99 71.12 0)
			(effects
				(font
					(size 1.27 1.27)
					(thickness 0.15)
				)
				(justify left bottom)
				(hide yes)
			)
		)
		(property "Footprint" "antmicro-footprints:R_0402_1005Metric"
			(at 173.99 73.66 0)
			(effects
				(font
					(size 1.27 1.27)
					(thickness 0.15)
				)
				(justify left bottom)
				(hide yes)
			)
		)
		(property "Datasheet" "https://www.bourns.com/docs/product-datasheets/cr.pdf"
			(at 173.99 76.2 0)
			(effects
				(font
					(size 1.27 1.27)
					(thickness 0.15)
				)
				(justify left bottom)
				(hide yes)
			)
		)
		(property "Description" "SMD Chip Resistor, 22 ohm, ± 1%, 62.5 mW, 0402 [1005 Metric], Thick Film, General Purpose"
			(at 153.67 58.42 0)
			(effects
				(font
					(size 1.27 1.27)
				)
				(hide yes)
			)
		)
		(property "MPN" "CR0402-FX-22R0GLF"
			(at 173.99 78.74 0)
			(effects
				(font
					(size 1.27 1.27)
					(thickness 0.15)
				)
				(justify left bottom)
				(hide yes)
			)
		)
		(property "Manufacturer" "Bourns"
			(at 173.99 81.28 0)
			(effects
				(font
					(size 1.27 1.27)
					(thickness 0.15)
				)
				(justify left bottom)
				(hide yes)
			)
		)
		(property "License" "Apache-2.0"
			(at 173.99 83.82 0)
			(effects
				(font
					(size 1.27 1.27)
					(thickness 0.15)
				)
				(justify left bottom)
				(hide yes)
			)
		)
		(property "Author" "Antmicro"
			(at 173.99 86.36 0)
			(effects
				(font
					(size 1.27 1.27)
					(thickness 0.15)
				)
				(justify left bottom)
				(hide yes)
			)
		)
		(property "Val" "22R"
			(at 158.75 57.15 0)
			(effects
				(font
					(size 1.27 1.27)
					(thickness 0.15)
				)
				(justify left)
			)
		)
		(property "Tolerance" "1%"
			(at 173.99 68.58 0)
			(effects
				(font
					(size 1.27 1.27)
				)
				(justify left bottom)
				(hide yes)
			)
		)
		(pin "2"
		)
		(pin "1"
		)
		(instances
			(project "OCuLink to 10GbE adapter"
				(path ""
					(reference "R84")
					(unit 1)
				)
			)
		)
	)
	(symbol
		(lib_id "antmicroResistors0402:R_3k3_0402")
		(at 64.77 114.3 90)
		(unit 1)
		(exclude_from_sim no)
		(in_bom yes)
		(on_board yes)
		(dnp no)
		(property "Reference" "R103"
			(at 66.04 110.49 90)
			(effects
				(font
					(size 1.27 1.27)
					(thickness 0.15)
				)
				(justify right)
			)
		)
		(property "Value" "R_3k3_0402"
			(at 77.47 93.98 0)
			(effects
				(font
					(size 1.27 1.27)
					(thickness 0.15)
				)
				(justify left bottom)
				(hide yes)
			)
		)
		(property "Footprint" "antmicro-footprints:R_0402_1005Metric"
			(at 80.01 93.98 0)
			(effects
				(font
					(size 1.27 1.27)
					(thickness 0.15)
				)
				(justify left bottom)
				(hide yes)
			)
		)
		(property "Datasheet" "https://www.bourns.com/docs/product-datasheets/cr.pdf"
			(at 82.55 93.98 0)
			(effects
				(font
					(size 1.27 1.27)
					(thickness 0.15)
				)
				(justify left bottom)
				(hide yes)
			)
		)
		(property "Description" "SMD Chip Resistor, 3.3 kohm, ± 1%, 63 mW, 0402 [1005 Metric], Thick Film, General Purpose"
			(at 64.77 114.3 0)
			(effects
				(font
					(size 1.27 1.27)
				)
				(hide yes)
			)
		)
		(property "MPN" "CR0402-FX-3301GLF"
			(at 85.09 93.98 0)
			(effects
				(font
					(size 1.27 1.27)
					(thickness 0.15)
				)
				(justify left bottom)
				(hide yes)
			)
		)
		(property "Manufacturer" "Bourns"
			(at 87.63 93.98 0)
			(effects
				(font
					(size 1.27 1.27)
					(thickness 0.15)
				)
				(justify left bottom)
				(hide yes)
			)
		)
		(property "License" "Apache-2.0"
			(at 90.17 93.98 0)
			(effects
				(font
					(size 1.27 1.27)
					(thickness 0.15)
				)
				(justify left bottom)
				(hide yes)
			)
		)
		(property "Author" "Antmicro"
			(at 92.71 93.98 0)
			(effects
				(font
					(size 1.27 1.27)
					(thickness 0.15)
				)
				(justify left bottom)
				(hide yes)
			)
		)
		(property "Val" "3k3"
			(at 66.04 113.03 90)
			(effects
				(font
					(size 1.27 1.27)
					(thickness 0.15)
				)
				(justify right)
			)
		)
		(property "Tolerance" "1%"
			(at 74.93 93.98 0)
			(effects
				(font
					(size 1.27 1.27)
				)
				(justify left bottom)
				(hide yes)
			)
		)
		(pin "2"
		)
		(pin "1"
		)
		(instances
			(project ""
				(path ""
					(reference "R103")
					(unit 1)
				)
			)
		)
	)
	(symbol
		(lib_id "antmicroResistors0402:R_0R_0402")
		(at 44.45 101.6 90)
		(unit 1)
		(exclude_from_sim no)
		(in_bom no)
		(on_board yes)
		(dnp yes)
		(property "Reference" "R172"
			(at 45.72 97.79 90)
			(effects
				(font
					(size 1.27 1.27)
					(thickness 0.15)
				)
				(justify right)
			)
		)
		(property "Value" "R_0R_0402"
			(at 57.15 81.28 0)
			(effects
				(font
					(size 1.27 1.27)
					(thickness 0.15)
				)
				(justify left bottom)
				(hide yes)
			)
		)
		(property "Footprint" "antmicro-footprints:R_0402_1005Metric"
			(at 59.69 81.28 0)
			(effects
				(font
					(size 1.27 1.27)
					(thickness 0.15)
				)
				(justify left bottom)
				(hide yes)
			)
		)
		(property "Datasheet" "https://industrial.panasonic.com/cdbs/www-data/pdf/RDA0000/AOA0000C301.pdf"
			(at 62.23 81.28 0)
			(effects
				(font
					(size 1.27 1.27)
					(thickness 0.15)
				)
				(justify left bottom)
				(hide yes)
			)
		)
		(property "Description" "SMD Chip Resistor, Jumper, 0 ohm, 100 mW, 0402 [1005 Metric], Thick Film, General Purpose"
			(at 44.45 101.6 0)
			(effects
				(font
					(size 1.27 1.27)
				)
				(hide yes)
			)
		)
		(property "MPN" "ERJ2GE0R00X"
			(at 64.77 81.28 0)
			(effects
				(font
					(size 1.27 1.27)
					(thickness 0.15)
				)
				(justify left bottom)
				(hide yes)
			)
		)
		(property "Manufacturer" "Panasonic"
			(at 67.31 81.28 0)
			(effects
				(font
					(size 1.27 1.27)
					(thickness 0.15)
				)
				(justify left bottom)
				(hide yes)
			)
		)
		(property "License" "Apache-2.0"
			(at 69.85 81.28 0)
			(effects
				(font
					(size 1.27 1.27)
					(thickness 0.15)
				)
				(justify left bottom)
				(hide yes)
			)
		)
		(property "Author" "Antmicro"
			(at 72.39 81.28 0)
			(effects
				(font
					(size 1.27 1.27)
					(thickness 0.15)
				)
				(justify left bottom)
				(hide yes)
			)
		)
		(property "Val" "0R"
			(at 45.72 100.33 90)
			(effects
				(font
					(size 1.27 1.27)
					(thickness 0.15)
				)
				(justify right)
			)
		)
		(property "Tolerance" "~"
			(at 54.61 81.28 0)
			(effects
				(font
					(size 1.27 1.27)
				)
				(justify left bottom)
				(hide yes)
			)
		)
		(property "Current" "1A"
			(at 74.93 81.28 0)
			(effects
				(font
					(size 1.27 1.27)
					(thickness 0.15)
				)
				(justify left bottom)
				(hide yes)
			)
		)
		(pin "1"
		)
		(pin "2"
		)
		(instances
			(project "OCuLink to 10GbE adapter"
				(path ""
					(reference "R172")
					(unit 1)
				)
			)
		)
	)
	(symbol
		(lib_id "antmicropower:+1V8")
		(at 106.68 210.82 0)
		(mirror y)
		(unit 1)
		(exclude_from_sim no)
		(in_bom yes)
		(on_board yes)
		(dnp no)
		(property "Reference" "#PWR098"
			(at 91.44 213.36 0)
			(effects
				(font
					(size 1.27 1.27)
					(thickness 0.15)
				)
				(justify left bottom)
				(hide yes)
			)
		)
		(property "Value" "+1V88"
			(at 106.68 207.01 0)
			(effects
				(font
					(size 1.27 1.27)
					(thickness 0.15)
				)
			)
		)
		(property "Footprint" ""
			(at 91.44 218.44 0)
			(effects
				(font
					(size 1.27 1.27)
					(thickness 0.15)
				)
				(justify left bottom)
				(hide yes)
			)
		)
		(property "Datasheet" ""
			(at 91.44 220.98 0)
			(effects
				(font
					(size 1.27 1.27)
					(thickness 0.15)
				)
				(justify left bottom)
				(hide yes)
			)
		)
		(property "Description" ""
			(at 106.68 210.82 0)
			(effects
				(font
					(size 1.27 1.27)
				)
				(hide yes)
			)
		)
		(property "Author" "Antmicro"
			(at 91.44 215.9 0)
			(effects
				(font
					(size 1.27 1.27)
					(thickness 0.15)
				)
				(justify left bottom)
				(hide yes)
			)
		)
		(property "License" "Apache-2.0"
			(at 91.44 218.44 0)
			(effects
				(font
					(size 1.27 1.27)
					(thickness 0.15)
				)
				(justify left bottom)
				(hide yes)
			)
		)
		(pin "1"
		)
		(instances
			(project "OCuLink to 10GbE adapter"
				(path ""
					(reference "#PWR098")
					(unit 1)
				)
			)
		)
	)
	(symbol
		(lib_id "antmicropower:GND")
		(at 140.97 246.38 0)
		(unit 1)
		(exclude_from_sim no)
		(in_bom yes)
		(on_board yes)
		(dnp no)
		(property "Reference" "#PWR0281"
			(at 149.86 248.92 0)
			(effects
				(font
					(size 1.27 1.27)
					(thickness 0.15)
				)
				(justify left bottom)
				(hide yes)
			)
		)
		(property "Value" "GND"
			(at 140.97 250.19 0)
			(effects
				(font
					(size 1.27 1.27)
					(thickness 0.15)
				)
			)
		)
		(property "Footprint" ""
			(at 149.86 254 0)
			(effects
				(font
					(size 1.27 1.27)
					(thickness 0.15)
				)
				(justify left bottom)
				(hide yes)
			)
		)
		(property "Datasheet" ""
			(at 149.86 259.08 0)
			(effects
				(font
					(size 1.27 1.27)
					(thickness 0.15)
				)
				(justify left bottom)
				(hide yes)
			)
		)
		(property "Description" ""
			(at 140.97 246.38 0)
			(effects
				(font
					(size 1.27 1.27)
				)
				(hide yes)
			)
		)
		(property "Author" "Antmicro"
			(at 149.86 254 0)
			(effects
				(font
					(size 1.27 1.27)
					(thickness 0.15)
				)
				(justify left bottom)
				(hide yes)
			)
		)
		(property "License" "Apache-2.0"
			(at 149.86 256.54 0)
			(effects
				(font
					(size 1.27 1.27)
					(thickness 0.15)
				)
				(justify left bottom)
				(hide yes)
			)
		)
		(pin "1"
		)
		(instances
			(project "OCuLink to 10GbE adapter"
				(path ""
					(reference "#PWR0281")
					(unit 1)
				)
			)
		)
	)
	(symbol
		(lib_id "antmicropower:GND")
		(at 64.77 132.08 0)
		(unit 1)
		(exclude_from_sim no)
		(in_bom yes)
		(on_board yes)
		(dnp no)
		(property "Reference" "#PWR0268"
			(at 73.66 134.62 0)
			(effects
				(font
					(size 1.27 1.27)
					(thickness 0.15)
				)
				(justify left bottom)
				(hide yes)
			)
		)
		(property "Value" "GND"
			(at 64.77 135.89 0)
			(effects
				(font
					(size 1.27 1.27)
					(thickness 0.15)
				)
			)
		)
		(property "Footprint" ""
			(at 73.66 139.7 0)
			(effects
				(font
					(size 1.27 1.27)
					(thickness 0.15)
				)
				(justify left bottom)
				(hide yes)
			)
		)
		(property "Datasheet" ""
			(at 73.66 144.78 0)
			(effects
				(font
					(size 1.27 1.27)
					(thickness 0.15)
				)
				(justify left bottom)
				(hide yes)
			)
		)
		(property "Description" ""
			(at 64.77 132.08 0)
			(effects
				(font
					(size 1.27 1.27)
				)
				(hide yes)
			)
		)
		(property "Author" "Antmicro"
			(at 73.66 139.7 0)
			(effects
				(font
					(size 1.27 1.27)
					(thickness 0.15)
				)
				(justify left bottom)
				(hide yes)
			)
		)
		(property "License" "Apache-2.0"
			(at 73.66 142.24 0)
			(effects
				(font
					(size 1.27 1.27)
					(thickness 0.15)
				)
				(justify left bottom)
				(hide yes)
			)
		)
		(pin "1"
		)
		(instances
			(project "OCuLink to 10GbE adapter"
				(path ""
					(reference "#PWR0268")
					(unit 1)
				)
			)
		)
	)
	(symbol
		(lib_id "antmicroCapacitors0402:C_100n_0402")
		(at 62.23 220.98 270)
		(mirror x)
		(unit 1)
		(exclude_from_sim no)
		(in_bom yes)
		(on_board yes)
		(dnp no)
		(property "Reference" "C75"
			(at 60.198 217.17 90)
			(effects
				(font
					(size 1.27 1.27)
					(thickness 0.15)
				)
				(justify right)
			)
		)
		(property "Value" "C_100n_0402"
			(at 39.37 205.74 0)
			(effects
				(font
					(size 1.27 1.27)
					(thickness 0.15)
				)
				(justify left bottom)
				(hide yes)
			)
		)
		(property "Footprint" "antmicro-footprints:C_0402_1005Metric"
			(at 36.83 205.74 0)
			(effects
				(font
					(size 1.27 1.27)
					(thickness 0.15)
				)
				(justify left bottom)
				(hide yes)
			)
		)
		(property "Datasheet" "https://www.murata.com/products/productdetail?partno=GRM155R61H104KE14%23"
			(at 34.29 205.74 0)
			(effects
				(font
					(size 1.27 1.27)
					(thickness 0.15)
				)
				(justify left bottom)
				(hide yes)
			)
		)
		(property "Description" "SMD Multilayer Ceramic Capacitor, 0.1 µF, 50 V, 0402 [1005 Metric], ± 10%, X5R, GRM Series"
			(at 62.23 220.98 0)
			(effects
				(font
					(size 1.27 1.27)
				)
				(hide yes)
			)
		)
		(property "MPN" "GRM155R61H104KE14D"
			(at 31.75 205.74 0)
			(effects
				(font
					(size 1.27 1.27)
					(thickness 0.15)
				)
				(justify left bottom)
				(hide yes)
			)
		)
		(property "Val" "100n"
			(at 60.198 219.71 90)
			(effects
				(font
					(size 1.27 1.27)
					(thickness 0.15)
				)
				(justify right)
			)
		)
		(property "Voltage" "50V"
			(at 52.07 205.74 0)
			(effects
				(font
					(size 1.27 1.27)
					(thickness 0.15)
				)
				(justify left bottom)
				(hide yes)
			)
		)
		(property "Dielectric" "X5R"
			(at 49.53 205.74 0)
			(effects
				(font
					(size 1.27 1.27)
					(thickness 0.15)
				)
				(justify left bottom)
				(hide yes)
			)
		)
		(property "Manufacturer" "Murata"
			(at 46.99 205.74 0)
			(effects
				(font
					(size 1.27 1.27)
					(thickness 0.15)
				)
				(justify left bottom)
				(hide yes)
			)
		)
		(property "License" "Apache-2.0"
			(at 44.45 205.74 0)
			(effects
				(font
					(size 1.27 1.27)
					(thickness 0.15)
				)
				(justify left bottom)
				(hide yes)
			)
		)
		(property "Author" "Antmicro"
			(at 41.91 205.74 0)
			(effects
				(font
					(size 1.27 1.27)
					(thickness 0.15)
				)
				(justify left bottom)
				(hide yes)
			)
		)
		(pin "2"
		)
		(pin "1"
		)
		(instances
			(project "OCuLink to 10GbE adapter"
				(path ""
					(reference "C75")
					(unit 1)
				)
			)
		)
	)
	(symbol
		(lib_id "antmicroResistors0402:R_22R_0402")
		(at 153.67 53.34 0)
		(unit 1)
		(exclude_from_sim no)
		(in_bom yes)
		(on_board yes)
		(dnp no)
		(property "Reference" "R83"
			(at 153.67 52.07 0)
			(effects
				(font
					(size 1.27 1.27)
					(thickness 0.15)
				)
				(justify right)
			)
		)
		(property "Value" "R_22R_0402"
			(at 173.99 66.04 0)
			(effects
				(font
					(size 1.27 1.27)
					(thickness 0.15)
				)
				(justify left bottom)
				(hide yes)
			)
		)
		(property "Footprint" "antmicro-footprints:R_0402_1005Metric"
			(at 173.99 68.58 0)
			(effects
				(font
					(size 1.27 1.27)
					(thickness 0.15)
				)
				(justify left bottom)
				(hide yes)
			)
		)
		(property "Datasheet" "https://www.bourns.com/docs/product-datasheets/cr.pdf"
			(at 173.99 71.12 0)
			(effects
				(font
					(size 1.27 1.27)
					(thickness 0.15)
				)
				(justify left bottom)
				(hide yes)
			)
		)
		(property "Description" "SMD Chip Resistor, 22 ohm, ± 1%, 62.5 mW, 0402 [1005 Metric], Thick Film, General Purpose"
			(at 153.67 53.34 0)
			(effects
				(font
					(size 1.27 1.27)
				)
				(hide yes)
			)
		)
		(property "MPN" "CR0402-FX-22R0GLF"
			(at 173.99 73.66 0)
			(effects
				(font
					(size 1.27 1.27)
					(thickness 0.15)
				)
				(justify left bottom)
				(hide yes)
			)
		)
		(property "Manufacturer" "Bourns"
			(at 173.99 76.2 0)
			(effects
				(font
					(size 1.27 1.27)
					(thickness 0.15)
				)
				(justify left bottom)
				(hide yes)
			)
		)
		(property "License" "Apache-2.0"
			(at 173.99 78.74 0)
			(effects
				(font
					(size 1.27 1.27)
					(thickness 0.15)
				)
				(justify left bottom)
				(hide yes)
			)
		)
		(property "Author" "Antmicro"
			(at 173.99 81.28 0)
			(effects
				(font
					(size 1.27 1.27)
					(thickness 0.15)
				)
				(justify left bottom)
				(hide yes)
			)
		)
		(property "Val" "22R"
			(at 158.75 52.07 0)
			(effects
				(font
					(size 1.27 1.27)
					(thickness 0.15)
				)
				(justify left)
			)
		)
		(property "Tolerance" "1%"
			(at 173.99 63.5 0)
			(effects
				(font
					(size 1.27 1.27)
				)
				(justify left bottom)
				(hide yes)
			)
		)
		(pin "2"
		)
		(pin "1"
		)
		(instances
			(project ""
				(path ""
					(reference "R83")
					(unit 1)
				)
			)
		)
	)
	(symbol
		(lib_id "antmicroTestPoints:TP_0.75mm_SMD")
		(at 170.18 228.6 180)
		(unit 1)
		(exclude_from_sim no)
		(in_bom no)
		(on_board yes)
		(dnp no)
		(property "Reference" "TP11"
			(at 165.862 228.6 0)
			(effects
				(font
					(size 1.27 1.27)
					(thickness 0.15)
				)
				(justify left)
			)
		)
		(property "Value" "TP_0.75mm_SMD"
			(at 160.02 224.79 0)
			(effects
				(font
					(size 1.27 1.27)
					(thickness 0.15)
				)
				(justify left bottom)
				(hide yes)
			)
		)
		(property "Footprint" "antmicro-footprints:TP_SMD_0.75mm"
			(at 160.02 222.25 0)
			(effects
				(font
					(size 1.27 1.27)
					(thickness 0.15)
				)
				(justify left bottom)
				(hide yes)
			)
		)
		(property "Datasheet" ""
			(at 152.4 215.9 0)
			(effects
				(font
					(size 1.27 1.27)
					(thickness 0.15)
				)
				(justify left bottom)
				(hide yes)
			)
		)
		(property "Description" "SMT test point"
			(at 170.18 228.6 0)
			(effects
				(font
					(size 1.27 1.27)
				)
				(hide yes)
			)
		)
		(property "MPN" ""
			(at 159.385 217.17 0)
			(effects
				(font
					(size 1.27 1.27)
					(thickness 0.15)
				)
				(justify left bottom)
				(hide yes)
			)
		)
		(property "Manufacturer" ""
			(at 159.385 222.25 0)
			(effects
				(font
					(size 1.27 1.27)
					(thickness 0.15)
				)
				(justify left bottom)
				(hide yes)
			)
		)
		(property "Author" "Antmicro"
			(at 160.02 219.71 0)
			(effects
				(font
					(size 1.27 1.27)
					(thickness 0.15)
				)
				(justify left bottom)
				(hide yes)
			)
		)
		(property "License" "Apache-2.0"
			(at 160.02 217.17 0)
			(effects
				(font
					(size 1.27 1.27)
					(thickness 0.15)
				)
				(justify left bottom)
				(hide yes)
			)
		)
		(pin "1"
		)
		(instances
			(project "OCuLink to 10GbE adapter"
				(path ""
					(reference "TP11")
					(unit 1)
				)
			)
		)
	)
	(symbol
		(lib_id "antmicropower:+3V3")
		(at 67.31 168.91 0)
		(mirror y)
		(unit 1)
		(exclude_from_sim no)
		(in_bom yes)
		(on_board yes)
		(dnp no)
		(property "Reference" "#PWR0108"
			(at 52.07 168.91 0)
			(effects
				(font
					(size 1.27 1.27)
					(thickness 0.15)
				)
				(justify left bottom)
				(hide yes)
			)
		)
		(property "Value" "+3V3"
			(at 67.31 165.1 0)
			(effects
				(font
					(size 1.27 1.27)
					(thickness 0.15)
				)
			)
		)
		(property "Footprint" ""
			(at 52.07 176.53 0)
			(effects
				(font
					(size 1.27 1.27)
					(thickness 0.15)
				)
				(justify left bottom)
				(hide yes)
			)
		)
		(property "Datasheet" ""
			(at 52.07 179.07 0)
			(effects
				(font
					(size 1.27 1.27)
					(thickness 0.15)
				)
				(justify left bottom)
				(hide yes)
			)
		)
		(property "Description" ""
			(at 67.31 168.91 0)
			(effects
				(font
					(size 1.27 1.27)
				)
				(hide yes)
			)
		)
		(property "Author" "Antmicro"
			(at 52.07 171.45 0)
			(effects
				(font
					(size 1.27 1.27)
					(thickness 0.15)
				)
				(justify left bottom)
				(hide yes)
			)
		)
		(property "License" "Apache-2.0"
			(at 52.07 173.99 0)
			(effects
				(font
					(size 1.27 1.27)
					(thickness 0.15)
				)
				(justify left bottom)
				(hide yes)
			)
		)
		(pin "1"
		)
		(instances
			(project "OCuLink to 10GbE adapter"
				(path ""
					(reference "#PWR0108")
					(unit 1)
				)
			)
		)
	)
	(symbol
		(lib_id "antmicroResistors0402:R_1k_0402")
		(at 245.11 157.48 90)
		(unit 1)
		(exclude_from_sim no)
		(in_bom yes)
		(on_board yes)
		(dnp no)
		(property "Reference" "R112"
			(at 246.634 153.67 90)
			(effects
				(font
					(size 1.27 1.27)
					(thickness 0.15)
				)
				(justify right)
			)
		)
		(property "Value" "R_1k_0402"
			(at 257.81 137.16 0)
			(effects
				(font
					(size 1.27 1.27)
					(thickness 0.15)
				)
				(justify left bottom)
				(hide yes)
			)
		)
		(property "Footprint" "antmicro-footprints:R_0402_1005Metric"
			(at 260.35 137.16 0)
			(effects
				(font
					(size 1.27 1.27)
					(thickness 0.15)
				)
				(justify left bottom)
				(hide yes)
			)
		)
		(property "Datasheet" "https://www.bourns.com/docs/product-datasheets/cr.pdf"
			(at 262.89 137.16 0)
			(effects
				(font
					(size 1.27 1.27)
					(thickness 0.15)
				)
				(justify left bottom)
				(hide yes)
			)
		)
		(property "Description" "SMD Chip Resistor, 1 kohm, ± 1%, 63 mW, 0402 [1005 Metric], Thick Film, General Purpose"
			(at 245.11 157.48 0)
			(effects
				(font
					(size 1.27 1.27)
				)
				(hide yes)
			)
		)
		(property "MPN" "CR0402-FX-1001GLF"
			(at 265.43 137.16 0)
			(effects
				(font
					(size 1.27 1.27)
					(thickness 0.15)
				)
				(justify left bottom)
				(hide yes)
			)
		)
		(property "Manufacturer" "Bourns"
			(at 267.97 137.16 0)
			(effects
				(font
					(size 1.27 1.27)
					(thickness 0.15)
				)
				(justify left bottom)
				(hide yes)
			)
		)
		(property "License" "Apache-2.0"
			(at 270.51 137.16 0)
			(effects
				(font
					(size 1.27 1.27)
					(thickness 0.15)
				)
				(justify left bottom)
				(hide yes)
			)
		)
		(property "Author" "Antmicro"
			(at 273.05 137.16 0)
			(effects
				(font
					(size 1.27 1.27)
					(thickness 0.15)
				)
				(justify left bottom)
				(hide yes)
			)
		)
		(property "Val" "1k"
			(at 246.634 156.21 90)
			(effects
				(font
					(size 1.27 1.27)
					(thickness 0.15)
				)
				(justify right)
			)
		)
		(property "Tolerance" "1%"
			(at 255.27 137.16 0)
			(effects
				(font
					(size 1.27 1.27)
				)
				(justify left bottom)
				(hide yes)
			)
		)
		(pin "2"
		)
		(pin "1"
		)
		(instances
			(project "OCuLink to 10GbE adapter"
				(path ""
					(reference "R112")
					(unit 1)
				)
			)
		)
	)
	(symbol
		(lib_id "antmicroResistors0402:R_0R_0402")
		(at 33.02 101.6 90)
		(unit 1)
		(exclude_from_sim no)
		(in_bom yes)
		(on_board yes)
		(dnp no)
		(property "Reference" "R173"
			(at 34.29 97.79 90)
			(effects
				(font
					(size 1.27 1.27)
					(thickness 0.15)
				)
				(justify right)
			)
		)
		(property "Value" "R_0R_0402"
			(at 45.72 81.28 0)
			(effects
				(font
					(size 1.27 1.27)
					(thickness 0.15)
				)
				(justify left bottom)
				(hide yes)
			)
		)
		(property "Footprint" "antmicro-footprints:R_0402_1005Metric"
			(at 48.26 81.28 0)
			(effects
				(font
					(size 1.27 1.27)
					(thickness 0.15)
				)
				(justify left bottom)
				(hide yes)
			)
		)
		(property "Datasheet" "https://industrial.panasonic.com/cdbs/www-data/pdf/RDA0000/AOA0000C301.pdf"
			(at 50.8 81.28 0)
			(effects
				(font
					(size 1.27 1.27)
					(thickness 0.15)
				)
				(justify left bottom)
				(hide yes)
			)
		)
		(property "Description" "SMD Chip Resistor, Jumper, 0 ohm, 100 mW, 0402 [1005 Metric], Thick Film, General Purpose"
			(at 33.02 101.6 0)
			(effects
				(font
					(size 1.27 1.27)
				)
				(hide yes)
			)
		)
		(property "MPN" "ERJ2GE0R00X"
			(at 53.34 81.28 0)
			(effects
				(font
					(size 1.27 1.27)
					(thickness 0.15)
				)
				(justify left bottom)
				(hide yes)
			)
		)
		(property "Manufacturer" "Panasonic"
			(at 55.88 81.28 0)
			(effects
				(font
					(size 1.27 1.27)
					(thickness 0.15)
				)
				(justify left bottom)
				(hide yes)
			)
		)
		(property "License" "Apache-2.0"
			(at 58.42 81.28 0)
			(effects
				(font
					(size 1.27 1.27)
					(thickness 0.15)
				)
				(justify left bottom)
				(hide yes)
			)
		)
		(property "Author" "Antmicro"
			(at 60.96 81.28 0)
			(effects
				(font
					(size 1.27 1.27)
					(thickness 0.15)
				)
				(justify left bottom)
				(hide yes)
			)
		)
		(property "Val" "0R"
			(at 34.29 100.33 90)
			(effects
				(font
					(size 1.27 1.27)
					(thickness 0.15)
				)
				(justify right)
			)
		)
		(property "Tolerance" "~"
			(at 43.18 81.28 0)
			(effects
				(font
					(size 1.27 1.27)
				)
				(justify left bottom)
				(hide yes)
			)
		)
		(property "Current" "1A"
			(at 63.5 81.28 0)
			(effects
				(font
					(size 1.27 1.27)
					(thickness 0.15)
				)
				(justify left bottom)
				(hide yes)
			)
		)
		(pin "1"
		)
		(pin "2"
		)
		(instances
			(project "OCuLink to 10GbE adapter"
				(path ""
					(reference "R173")
					(unit 1)
				)
			)
		)
	)
	(symbol
		(lib_id "antmicropower:GND")
		(at 33.02 114.3 0)
		(unit 1)
		(exclude_from_sim no)
		(in_bom yes)
		(on_board yes)
		(dnp no)
		(property "Reference" "#PWR0267"
			(at 41.91 116.84 0)
			(effects
				(font
					(size 1.27 1.27)
					(thickness 0.15)
				)
				(justify left bottom)
				(hide yes)
			)
		)
		(property "Value" "GND"
			(at 33.02 118.11 0)
			(effects
				(font
					(size 1.27 1.27)
					(thickness 0.15)
				)
			)
		)
		(property "Footprint" ""
			(at 41.91 121.92 0)
			(effects
				(font
					(size 1.27 1.27)
					(thickness 0.15)
				)
				(justify left bottom)
				(hide yes)
			)
		)
		(property "Datasheet" ""
			(at 41.91 127 0)
			(effects
				(font
					(size 1.27 1.27)
					(thickness 0.15)
				)
				(justify left bottom)
				(hide yes)
			)
		)
		(property "Description" ""
			(at 33.02 114.3 0)
			(effects
				(font
					(size 1.27 1.27)
				)
				(hide yes)
			)
		)
		(property "Author" "Antmicro"
			(at 41.91 121.92 0)
			(effects
				(font
					(size 1.27 1.27)
					(thickness 0.15)
				)
				(justify left bottom)
				(hide yes)
			)
		)
		(property "License" "Apache-2.0"
			(at 41.91 124.46 0)
			(effects
				(font
					(size 1.27 1.27)
					(thickness 0.15)
				)
				(justify left bottom)
				(hide yes)
			)
		)
		(pin "1"
		)
		(instances
			(project "OCuLink to 10GbE adapter"
				(path ""
					(reference "#PWR0267")
					(unit 1)
				)
			)
		)
	)
	(symbol
		(lib_id "antmicroResistors0402:R_2k_0402")
		(at 160.02 185.42 270)
		(mirror x)
		(unit 1)
		(exclude_from_sim no)
		(in_bom yes)
		(on_board yes)
		(dnp no)
		(property "Reference" "R114"
			(at 158.496 181.61 90)
			(effects
				(font
					(size 1.27 1.27)
					(thickness 0.15)
				)
				(justify right)
			)
		)
		(property "Value" "R_2k_0402"
			(at 147.32 165.1 0)
			(effects
				(font
					(size 1.27 1.27)
					(thickness 0.15)
				)
				(justify left bottom)
				(hide yes)
			)
		)
		(property "Footprint" "antmicro-footprints:R_0402_1005Metric"
			(at 144.78 165.1 0)
			(effects
				(font
					(size 1.27 1.27)
					(thickness 0.15)
				)
				(justify left bottom)
				(hide yes)
			)
		)
		(property "Datasheet" "https://www.bourns.com/docs/product-datasheets/cr.pdf"
			(at 142.24 165.1 0)
			(effects
				(font
					(size 1.27 1.27)
					(thickness 0.15)
				)
				(justify left bottom)
				(hide yes)
			)
		)
		(property "Description" "SMD Chip Resistor, 2 kohm, ± 1%, 62.5 mW, 0402 [1005 Metric], Thick Film, General Purpose"
			(at 160.02 185.42 0)
			(effects
				(font
					(size 1.27 1.27)
				)
				(hide yes)
			)
		)
		(property "MPN" "CR0402-FX-2001GLF"
			(at 139.7 165.1 0)
			(effects
				(font
					(size 1.27 1.27)
					(thickness 0.15)
				)
				(justify left bottom)
				(hide yes)
			)
		)
		(property "Manufacturer" "Bourns"
			(at 137.16 165.1 0)
			(effects
				(font
					(size 1.27 1.27)
					(thickness 0.15)
				)
				(justify left bottom)
				(hide yes)
			)
		)
		(property "License" "Apache-2.0"
			(at 134.62 165.1 0)
			(effects
				(font
					(size 1.27 1.27)
					(thickness 0.15)
				)
				(justify left bottom)
				(hide yes)
			)
		)
		(property "Author" "Antmicro"
			(at 132.08 165.1 0)
			(effects
				(font
					(size 1.27 1.27)
					(thickness 0.15)
				)
				(justify left bottom)
				(hide yes)
			)
		)
		(property "Val" "2k"
			(at 158.496 184.15 90)
			(effects
				(font
					(size 1.27 1.27)
					(thickness 0.15)
				)
				(justify right)
			)
		)
		(property "Tolerance" "1%"
			(at 149.86 165.1 0)
			(effects
				(font
					(size 1.27 1.27)
				)
				(justify left bottom)
				(hide yes)
			)
		)
		(pin "1"
		)
		(pin "2"
		)
		(instances
			(project "OCuLink to 10GbE adapter"
				(path ""
					(reference "R114")
					(unit 1)
				)
			)
		)
	)
	(symbol
		(lib_id "antmicroResistors0402:R_100R_0402")
		(at 99.06 232.41 0)
		(unit 1)
		(exclude_from_sim no)
		(in_bom yes)
		(on_board yes)
		(dnp no)
		(property "Reference" "R49"
			(at 99.06 231.14 0)
			(effects
				(font
					(size 1.27 1.27)
					(thickness 0.15)
				)
				(justify right)
			)
		)
		(property "Value" "R_100R_0402"
			(at 119.38 245.11 0)
			(effects
				(font
					(size 1.27 1.27)
					(thickness 0.15)
				)
				(justify left bottom)
				(hide yes)
			)
		)
		(property "Footprint" "antmicro-footprints:R_0402_1005Metric"
			(at 119.38 247.65 0)
			(effects
				(font
					(size 1.27 1.27)
					(thickness 0.15)
				)
				(justify left bottom)
				(hide yes)
			)
		)
		(property "Datasheet" "https://www.bourns.com/docs/product-datasheets/cr.pdf"
			(at 119.38 250.19 0)
			(effects
				(font
					(size 1.27 1.27)
					(thickness 0.15)
				)
				(justify left bottom)
				(hide yes)
			)
		)
		(property "Description" "SMD Chip Resistor, 100 ohm, ± 1%, 62.5 mW, 0402 [1005 Metric], Thick Film, General Purpose"
			(at 119.38 262.89 0)
			(effects
				(font
					(size 1.27 1.27)
				)
				(justify left bottom)
				(hide yes)
			)
		)
		(property "MPN" "CR0402-FX-1000GLF"
			(at 119.38 252.73 0)
			(effects
				(font
					(size 1.27 1.27)
					(thickness 0.15)
				)
				(justify left bottom)
				(hide yes)
			)
		)
		(property "Manufacturer" "Bourns"
			(at 119.38 255.27 0)
			(effects
				(font
					(size 1.27 1.27)
					(thickness 0.15)
				)
				(justify left bottom)
				(hide yes)
			)
		)
		(property "License" "Apache-2.0"
			(at 119.38 257.81 0)
			(effects
				(font
					(size 1.27 1.27)
					(thickness 0.15)
				)
				(justify left bottom)
				(hide yes)
			)
		)
		(property "Author" "Antmicro"
			(at 119.38 260.35 0)
			(effects
				(font
					(size 1.27 1.27)
					(thickness 0.15)
				)
				(justify left bottom)
				(hide yes)
			)
		)
		(property "Val" "100R"
			(at 104.14 231.14 0)
			(effects
				(font
					(size 1.27 1.27)
					(thickness 0.15)
				)
				(justify left)
			)
		)
		(property "Tolerance" "1%"
			(at 119.38 242.57 0)
			(effects
				(font
					(size 1.27 1.27)
				)
				(justify left bottom)
				(hide yes)
			)
		)
		(pin "2"
		)
		(pin "1"
		)
		(instances
			(project "OCuLink to 10GbE adapter"
				(path ""
					(reference "R49")
					(unit 1)
				)
			)
		)
	)
	(symbol
		(lib_id "antmicropower:GND")
		(at 119.38 175.26 0)
		(unit 1)
		(exclude_from_sim no)
		(in_bom yes)
		(on_board yes)
		(dnp no)
		(property "Reference" "#PWR095"
			(at 128.27 177.8 0)
			(effects
				(font
					(size 1.27 1.27)
					(thickness 0.15)
				)
				(justify left bottom)
				(hide yes)
			)
		)
		(property "Value" "GND"
			(at 119.38 179.07 0)
			(effects
				(font
					(size 1.27 1.27)
					(thickness 0.15)
				)
			)
		)
		(property "Footprint" ""
			(at 128.27 182.88 0)
			(effects
				(font
					(size 1.27 1.27)
					(thickness 0.15)
				)
				(justify left bottom)
				(hide yes)
			)
		)
		(property "Datasheet" ""
			(at 128.27 187.96 0)
			(effects
				(font
					(size 1.27 1.27)
					(thickness 0.15)
				)
				(justify left bottom)
				(hide yes)
			)
		)
		(property "Description" ""
			(at 119.38 175.26 0)
			(effects
				(font
					(size 1.27 1.27)
				)
				(hide yes)
			)
		)
		(property "Author" "Antmicro"
			(at 128.27 182.88 0)
			(effects
				(font
					(size 1.27 1.27)
					(thickness 0.15)
				)
				(justify left bottom)
				(hide yes)
			)
		)
		(property "License" "Apache-2.0"
			(at 128.27 185.42 0)
			(effects
				(font
					(size 1.27 1.27)
					(thickness 0.15)
				)
				(justify left bottom)
				(hide yes)
			)
		)
		(pin "1"
		)
		(instances
			(project "OCuLink to 10GbE adapter"
				(path ""
					(reference "#PWR095")
					(unit 1)
				)
			)
		)
	)
	(symbol
		(lib_id "antmicroInterfaceControllers:EZX710AT2_S_LMR5")
		(at 187.96 73.66 0)
		(unit 4)
		(exclude_from_sim no)
		(in_bom yes)
		(on_board yes)
		(dnp no)
		(fields_autoplaced yes)
		(property "Reference" "U9"
			(at 214.63 66.04 0)
			(effects
				(font
					(size 1.27 1.27)
					(thickness 0.15)
				)
			)
		)
		(property "Value" "EZX710AT2_S_LMR5"
			(at 264.16 78.74 0)
			(effects
				(font
					(size 1.27 1.27)
					(thickness 0.15)
				)
				(justify left bottom)
				(hide yes)
			)
		)
		(property "Footprint" "antmicro-footprints:FCBGA-503_22x22mm_Layout21x24_P1mm"
			(at 264.16 81.28 0)
			(effects
				(font
					(size 1.27 1.27)
					(thickness 0.15)
				)
				(justify left bottom)
				(hide yes)
			)
		)
		(property "Datasheet" "https://www.google.com/url?sa=t&source=web&rct=j&opi=89978449&url=https://cdrdv2-public.intel.com/596333/596333_X710-TM4_Datasheet_v_2_4.pdf&ved=2ahUKEwiSuv20_sCOAxXVCRAIHdxGO_UQFnoECBEQAQ&usg=AOvVaw1CjGyrGWE8ZvOdw4VBsY6U"
			(at 264.16 83.82 0)
			(effects
				(font
					(size 1.27 1.27)
					(thickness 0.15)
				)
				(justify left bottom)
				(hide yes)
			)
		)
		(property "Description" "Ethernet ICs Intel Ethernet Controller 10 Gigabit X7"
			(at 264.16 86.36 0)
			(effects
				(font
					(size 1.27 1.27)
					(thickness 0.15)
				)
				(justify left bottom)
				(hide yes)
			)
		)
		(property "MPN" "EZX710AT2 S LMR5"
			(at 214.63 68.58 0)
			(effects
				(font
					(size 1.27 1.27)
					(thickness 0.15)
				)
			)
		)
		(property "Manufacturer" "Intel"
			(at 264.16 88.9 0)
			(effects
				(font
					(size 1.27 1.27)
					(thickness 0.15)
				)
				(justify left bottom)
				(hide yes)
			)
		)
		(property "Author" "Antmicro"
			(at 264.16 91.44 0)
			(effects
				(font
					(size 1.27 1.27)
					(thickness 0.15)
				)
				(justify left bottom)
				(hide yes)
			)
		)
		(property "License" "Apache-2.0"
			(at 264.16 93.98 0)
			(effects
				(font
					(size 1.27 1.27)
					(thickness 0.15)
				)
				(justify left bottom)
				(hide yes)
			)
		)
		(pin "B26"
		)
		(pin "E7"
		)
		(pin "G9"
		)
		(pin "E5"
		)
		(pin "A17"
		)
		(pin "J15"
		)
		(pin "P34"
		)
		(pin "AD30"
		)
		(pin "J7"
		)
		(pin "C1"
		)
		(pin "G37"
		)
		(pin "N37"
		)
		(pin "F38"
		)
		(pin "B2"
		)
		(pin "N29"
		)
		(pin "D4"
		)
		(pin "Y24"
		)
		(pin "N35"
		)
		(pin "C5"
		)
		(pin "V42"
		)
		(pin "M20"
		)
		(pin "P10"
		)
		(pin "L37"
		)
		(pin "B34"
		)
		(pin "U37"
		)
		(pin "AC7"
		)
		(pin "M4"
		)
		(pin "U35"
		)
		(pin "D18"
		)
		(pin "H16"
		)
		(pin "V30"
		)
		(pin "B38"
		)
		(pin "W29"
		)
		(pin "AB22"
		)
		(pin "AC15"
		)
		(pin "B28"
		)
		(pin "G3"
		)
		(pin "P32"
		)
		(pin "H14"
		)
		(pin "G13"
		)
		(pin "B30"
		)
		(pin "D22"
		)
		(pin "V10"
		)
		(pin "B24"
		)
		(pin "AD4"
		)
		(pin "AC5"
		)
		(pin "AA5"
		)
		(pin "V24"
		)
		(pin "V6"
		)
		(pin "D10"
		)
		(pin "AD20"
		)
		(pin "T26"
		)
		(pin "T10"
		)
		(pin "T12"
		)
		(pin "AD6"
		)
		(pin "H8"
		)
		(pin "H28"
		)
		(pin "N15"
		)
		(pin "AC29"
		)
		(pin "N17"
		)
		(pin "W31"
		)
		(pin "Y12"
		)
		(pin "W23"
		)
		(pin "AD32"
		)
		(pin "AB16"
		)
		(pin "T28"
		)
		(pin "D24"
		)
		(pin "D26"
		)
		(pin "G17"
		)
		(pin "K32"
		)
		(pin "F24"
		)
		(pin "F26"
		)
		(pin "J31"
		)
		(pin "T30"
		)
		(pin "AD34"
		)
		(pin "AA27"
		)
		(pin "R17"
		)
		(pin "W13"
		)
		(pin "M26"
		)
		(pin "C9"
		)
		(pin "AA41"
		)
		(pin "AC27"
		)
		(pin "K2"
		)
		(pin "AB20"
		)
		(pin "R7"
		)
		(pin "N39"
		)
		(pin "D6"
		)
		(pin "M22"
		)
		(pin "M2"
		)
		(pin "AC9"
		)
		(pin "A3"
		)
		(pin "P2"
		)
		(pin "AA33"
		)
		(pin "A23"
		)
		(pin "E35"
		)
		(pin "U3"
		)
		(pin "V36"
		)
		(pin "K42"
		)
		(pin "R41"
		)
		(pin "R1"
		)
		(pin "AD22"
		)
		(pin "W7"
		)
		(pin "AB18"
		)
		(pin "E19"
		)
		(pin "AB12"
		)
		(pin "AD28"
		)
		(pin "AD40"
		)
		(pin "J1"
		)
		(pin "Y6"
		)
		(pin "Y8"
		)
		(pin "H36"
		)
		(pin "C13"
		)
		(pin "C23"
		)
		(pin "Y38"
		)
		(pin "U21"
		)
		(pin "F32"
		)
		(pin "F34"
		)
		(pin "A25"
		)
		(pin "N23"
		)
		(pin "W41"
		)
		(pin "AC31"
		)
		(pin "D12"
		)
		(pin "K34"
		)
		(pin "AA23"
		)
		(pin "AC17"
		)
		(pin "V22"
		)
		(pin "AA39"
		)
		(pin "J41"
		)
		(pin "V14"
		)
		(pin "U23"
		)
		(pin "V16"
		)
		(pin "W35"
		)
		(pin "AC21"
		)
		(pin "D32"
		)
		(pin "L1"
		)
		(pin "P24"
		)
		(pin "J3"
		)
		(pin "AC41"
		)
		(pin "AD14"
		)
		(pin "K22"
		)
		(pin "A11"
		)
		(pin "AA15"
		)
		(pin "F2"
		)
		(pin "A9"
		)
		(pin "N27"
		)
		(pin "C19"
		)
		(pin "K30"
		)
		(pin "L23"
		)
		(pin "N41"
		)
		(pin "F20"
		)
		(pin "AB28"
		)
		(pin "AD12"
		)
		(pin "C21"
		)
		(pin "U9"
		)
		(pin "V20"
		)
		(pin "D20"
		)
		(pin "L21"
		)
		(pin "R15"
		)
		(pin "K4"
		)
		(pin "N1"
		)
		(pin "H12"
		)
		(pin "J23"
		)
		(pin "J5"
		)
		(pin "E9"
		)
		(pin "M28"
		)
		(pin "U1"
		)
		(pin "Y2"
		)
		(pin "G5"
		)
		(pin "K20"
		)
		(pin "M18"
		)
		(pin "V2"
		)
		(pin "AC39"
		)
		(pin "T32"
		)
		(pin "E25"
		)
		(pin "AD38"
		)
		(pin "H26"
		)
		(pin "AA31"
		)
		(pin "G31"
		)
		(pin "U27"
		)
		(pin "U17"
		)
		(pin "C11"
		)
		(pin "N3"
		)
		(pin "A37"
		)
		(pin "F6"
		)
		(pin "Y30"
		)
		(pin "U7"
		)
		(pin "G15"
		)
		(pin "C29"
		)
		(pin "E39"
		)
		(pin "A35"
		)
		(pin "L3"
		)
		(pin "N25"
		)
		(pin "R25"
		)
		(pin "J37"
		)
		(pin "H42"
		)
		(pin "AD24"
		)
		(pin "B14"
		)
		(pin "P6"
		)
		(pin "R31"
		)
		(pin "A5"
		)
		(pin "D14"
		)
		(pin "AB10"
		)
		(pin "B18"
		)
		(pin "A27"
		)
		(pin "T40"
		)
		(pin "AB40"
		)
		(pin "P4"
		)
		(pin "AA35"
		)
		(pin "F36"
		)
		(pin "K18"
		)
		(pin "K38"
		)
		(pin "N33"
		)
		(pin "Y26"
		)
		(pin "Y28"
		)
		(pin "G21"
		)
		(pin "AA1"
		)
		(pin "AB2"
		)
		(pin "V38"
		)
		(pin "J9"
		)
		(pin "B6"
		)
		(pin "L35"
		)
		(pin "N7"
		)
		(pin "AC1"
		)
		(pin "E23"
		)
		(pin "F40"
		)
		(pin "F42"
		)
		(pin "P36"
		)
		(pin "F4"
		)
		(pin "AD16"
		)
		(pin "R11"
		)
		(pin "R27"
		)
		(pin "J13"
		)
		(pin "V34"
		)
		(pin "M10"
		)
		(pin "Y4"
		)
		(pin "Y40"
		)
		(pin "L27"
		)
		(pin "L9"
		)
		(pin "K10"
		)
		(pin "L39"
		)
		(pin "U5"
		)
		(pin "AB42"
		)
		(pin "R5"
		)
		(pin "G23"
		)
		(pin "M8"
		)
		(pin "AD8"
		)
		(pin "M16"
		)
		(pin "M12"
		)
		(pin "E3"
		)
		(pin "B12"
		)
		(pin "R23"
		)
		(pin "W25"
		)
		(pin "H4"
		)
		(pin "F8"
		)
		(pin "AC23"
		)
		(pin "AA3"
		)
		(pin "B10"
		)
		(pin "E31"
		)
		(pin "E33"
		)
		(pin "G1"
		)
		(pin "F18"
		)
		(pin "W17"
		)
		(pin "K36"
		)
		(pin "AB26"
		)
		(pin "R13"
		)
		(pin "AB32"
		)
		(pin "V18"
		)
		(pin "D16"
		)
		(pin "AA37"
		)
		(pin "C31"
		)
		(pin "C41"
		)
		(pin "A41"
		)
		(pin "E1"
		)
		(pin "P38"
		)
		(pin "U19"
		)
		(pin "R29"
		)
		(pin "E37"
		)
		(pin "E29"
		)
		(pin "A21"
		)
		(pin "A31"
		)
		(pin "U29"
		)
		(pin "AB34"
		)
		(pin "E17"
		)
		(pin "W15"
		)
		(pin "H40"
		)
		(pin "M24"
		)
		(pin "U15"
		)
		(pin "H2"
		)
		(pin "N21"
		)
		(pin "W33"
		)
		(pin "J29"
		)
		(pin "T42"
		)
		(pin "A13"
		)
		(pin "AD26"
		)
		(pin "P28"
		)
		(pin "T24"
		)
		(pin "F12"
		)
		(pin "AD2"
		)
		(pin "H34"
		)
		(pin "J33"
		)
		(pin "P40"
		)
		(pin "C17"
		)
		(pin "W19"
		)
		(pin "M6"
		)
		(pin "H6"
		)
		(pin "M40"
		)
		(pin "D30"
		)
		(pin "F10"
		)
		(pin "Y14"
		)
		(pin "L29"
		)
		(pin "P22"
		)
		(pin "W1"
		)
		(pin "V28"
		)
		(pin "E11"
		)
		(pin "J25"
		)
		(pin "G27"
		)
		(pin "M34"
		)
		(pin "Y18"
		)
		(pin "K8"
		)
		(pin "AC35"
		)
		(pin "AD36"
		)
		(pin "G19"
		)
		(pin "G41"
		)
		(pin "W3"
		)
		(pin "C37"
		)
		(pin "C27"
		)
		(pin "Y22"
		)
		(pin "C35"
		)
		(pin "L41"
		)
		(pin "P30"
		)
		(pin "V8"
		)
		(pin "AB30"
		)
		(pin "A29"
		)
		(pin "B22"
		)
		(pin "B32"
		)
		(pin "T36"
		)
		(pin "AA17"
		)
		(pin "K12"
		)
		(pin "P8"
		)
		(pin "T22"
		)
		(pin "C15"
		)
		(pin "W9"
		)
		(pin "W11"
		)
		(pin "P42"
		)
		(pin "T6"
		)
		(pin "B40"
		)
		(pin "N9"
		)
		(pin "K6"
		)
		(pin "A33"
		)
		(pin "T38"
		)
		(pin "J35"
		)
		(pin "E41"
		)
		(pin "T2"
		)
		(pin "C3"
		)
		(pin "R3"
		)
		(pin "D8"
		)
		(pin "F28"
		)
		(pin "F30"
		)
		(pin "Y32"
		)
		(pin "Y36"
		)
		(pin "AC25"
		)
		(pin "T4"
		)
		(pin "V26"
		)
		(pin "B16"
		)
		(pin "V32"
		)
		(pin "H10"
		)
		(pin "A7"
		)
		(pin "R9"
		)
		(pin "N11"
		)
		(pin "R37"
		)
		(pin "W37"
		)
		(pin "V4"
		)
		(pin "T14"
		)
		(pin "T16"
		)
		(pin "J21"
		)
		(pin "AB14"
		)
		(pin "J17"
		)
		(pin "W5"
		)
		(pin "D34"
		)
		(pin "Y34"
		)
		(pin "M36"
		)
		(pin "AA25"
		)
		(pin "B4"
		)
		(pin "AA29"
		)
		(pin "K16"
		)
		(pin "V40"
		)
		(pin "AC37"
		)
		(pin "AB24"
		)
		(pin "AD18"
		)
		(pin "AA7"
		)
		(pin "V12"
		)
		(pin "AC13"
		)
		(pin "T8"
		)
		(pin "E21"
		)
		(pin "A19"
		)
		(pin "E27"
		)
		(pin "K14"
		)
		(pin "AA13"
		)
		(pin "P16"
		)
		(pin "P18"
		)
		(pin "H30"
		)
		(pin "N31"
		)
		(pin "P12"
		)
		(pin "P14"
		)
		(pin "B42"
		)
		(pin "G25"
		)
		(pin "U25"
		)
		(pin "A39"
		)
		(pin "J11"
		)
		(pin "G11"
		)
		(pin "G29"
		)
		(pin "R19"
		)
		(pin "AC11"
		)
		(pin "F22"
		)
		(pin "W39"
		)
		(pin "AA9"
		)
		(pin "AB38"
		)
		(pin "L31"
		)
		(pin "T34"
		)
		(pin "J39"
		)
		(pin "F14"
		)
		(pin "H24"
		)
		(pin "G35"
		)
		(pin "W21"
		)
		(pin "K40"
		)
		(pin "N19"
		)
		(pin "B20"
		)
		(pin "U31"
		)
		(pin "R21"
		)
		(pin "R39"
		)
		(pin "P20"
		)
		(pin "R35"
		)
		(pin "AD42"
		)
		(pin "K24"
		)
		(pin "AB4"
		)
		(pin "AC33"
		)
		(pin "B8"
		)
		(pin "U33"
		)
		(pin "H32"
		)
		(pin "L33"
		)
		(pin "J19"
		)
		(pin "U13"
		)
		(pin "C39"
		)
		(pin "H22"
		)
		(pin "AD10"
		)
		(pin "Y20"
		)
		(pin "E15"
		)
		(pin "AA21"
		)
		(pin "K26"
		)
		(pin "C25"
		)
		(pin "M42"
		)
		(pin "U41"
		)
		(pin "Y16"
		)
		(pin "D28"
		)
		(pin "D36"
		)
		(pin "Y10"
		)
		(pin "AC19"
		)
		(pin "AB8"
		)
		(pin "AB36"
		)
		(pin "P26"
		)
		(pin "D38"
		)
		(pin "D40"
		)
		(pin "AA19"
		)
		(pin "E13"
		)
		(pin "A15"
		)
		(pin "H20"
		)
		(pin "K28"
		)
		(pin "F16"
		)
		(pin "W27"
		)
		(pin "D42"
		)
		(pin "AB6"
		)
		(pin "M14"
		)
		(pin "M32"
		)
		(pin "N5"
		)
		(pin "U11"
		)
		(pin "J27"
		)
		(pin "M30"
		)
		(pin "C33"
		)
		(pin "C7"
		)
		(pin "L15"
		)
		(pin "G33"
		)
		(pin "L19"
		)
		(pin "L17"
		)
		(pin "L5"
		)
		(pin "L25"
		)
		(pin "M38"
		)
		(pin "T18"
		)
		(pin "T20"
		)
		(pin "H18"
		)
		(pin "G7"
		)
		(pin "B36"
		)
		(pin "U39"
		)
		(pin "G39"
		)
		(pin "D2"
		)
		(pin "R33"
		)
		(pin "L11"
		)
		(pin "AC3"
		)
		(pin "AA11"
		)
		(pin "H38"
		)
		(pin "N13"
		)
		(pin "L13"
		)
		(pin "L7"
		)
		(pin "Y42"
		)
		(instances
			(project "OCuLink to 10GbE adapter"
				(path ""
					(reference "U9")
					(unit 4)
				)
			)
		)
	)
	(symbol
		(lib_id "antmicroInterfaceControllers:EZX710AT2_S_LMR5")
		(at 182.88 160.02 0)
		(unit 6)
		(exclude_from_sim no)
		(in_bom yes)
		(on_board yes)
		(dnp no)
		(fields_autoplaced yes)
		(property "Reference" "U9"
			(at 210.82 152.4 0)
			(effects
				(font
					(size 1.27 1.27)
					(thickness 0.15)
				)
			)
		)
		(property "Value" "EZX710AT2_S_LMR5"
			(at 259.08 165.1 0)
			(effects
				(font
					(size 1.27 1.27)
					(thickness 0.15)
				)
				(justify left bottom)
				(hide yes)
			)
		)
		(property "Footprint" "antmicro-footprints:FCBGA-503_22x22mm_Layout21x24_P1mm"
			(at 259.08 167.64 0)
			(effects
				(font
					(size 1.27 1.27)
					(thickness 0.15)
				)
				(justify left bottom)
				(hide yes)
			)
		)
		(property "Datasheet" "https://www.google.com/url?sa=t&source=web&rct=j&opi=89978449&url=https://cdrdv2-public.intel.com/596333/596333_X710-TM4_Datasheet_v_2_4.pdf&ved=2ahUKEwiSuv20_sCOAxXVCRAIHdxGO_UQFnoECBEQAQ&usg=AOvVaw1CjGyrGWE8ZvOdw4VBsY6U"
			(at 259.08 170.18 0)
			(effects
				(font
					(size 1.27 1.27)
					(thickness 0.15)
				)
				(justify left bottom)
				(hide yes)
			)
		)
		(property "Description" "Ethernet ICs Intel Ethernet Controller 10 Gigabit X7"
			(at 259.08 172.72 0)
			(effects
				(font
					(size 1.27 1.27)
					(thickness 0.15)
				)
				(justify left bottom)
				(hide yes)
			)
		)
		(property "MPN" "EZX710AT2 S LMR5"
			(at 210.82 154.94 0)
			(effects
				(font
					(size 1.27 1.27)
					(thickness 0.15)
				)
			)
		)
		(property "Manufacturer" "Intel"
			(at 259.08 175.26 0)
			(effects
				(font
					(size 1.27 1.27)
					(thickness 0.15)
				)
				(justify left bottom)
				(hide yes)
			)
		)
		(property "Author" "Antmicro"
			(at 259.08 177.8 0)
			(effects
				(font
					(size 1.27 1.27)
					(thickness 0.15)
				)
				(justify left bottom)
				(hide yes)
			)
		)
		(property "License" "Apache-2.0"
			(at 259.08 180.34 0)
			(effects
				(font
					(size 1.27 1.27)
					(thickness 0.15)
				)
				(justify left bottom)
				(hide yes)
			)
		)
		(pin "B26"
		)
		(pin "E7"
		)
		(pin "G9"
		)
		(pin "E5"
		)
		(pin "A17"
		)
		(pin "J15"
		)
		(pin "P34"
		)
		(pin "AD30"
		)
		(pin "J7"
		)
		(pin "C1"
		)
		(pin "G37"
		)
		(pin "N37"
		)
		(pin "F38"
		)
		(pin "B2"
		)
		(pin "N29"
		)
		(pin "D4"
		)
		(pin "Y24"
		)
		(pin "N35"
		)
		(pin "C5"
		)
		(pin "V42"
		)
		(pin "M20"
		)
		(pin "P10"
		)
		(pin "L37"
		)
		(pin "B34"
		)
		(pin "U37"
		)
		(pin "AC7"
		)
		(pin "M4"
		)
		(pin "U35"
		)
		(pin "D18"
		)
		(pin "H16"
		)
		(pin "V30"
		)
		(pin "B38"
		)
		(pin "W29"
		)
		(pin "AB22"
		)
		(pin "AC15"
		)
		(pin "B28"
		)
		(pin "G3"
		)
		(pin "P32"
		)
		(pin "H14"
		)
		(pin "G13"
		)
		(pin "B30"
		)
		(pin "D22"
		)
		(pin "V10"
		)
		(pin "B24"
		)
		(pin "AD4"
		)
		(pin "AC5"
		)
		(pin "AA5"
		)
		(pin "V24"
		)
		(pin "V6"
		)
		(pin "D10"
		)
		(pin "AD20"
		)
		(pin "T26"
		)
		(pin "T10"
		)
		(pin "T12"
		)
		(pin "AD6"
		)
		(pin "H8"
		)
		(pin "H28"
		)
		(pin "N15"
		)
		(pin "AC29"
		)
		(pin "N17"
		)
		(pin "W31"
		)
		(pin "Y12"
		)
		(pin "W23"
		)
		(pin "AD32"
		)
		(pin "AB16"
		)
		(pin "T28"
		)
		(pin "D24"
		)
		(pin "D26"
		)
		(pin "G17"
		)
		(pin "K32"
		)
		(pin "F24"
		)
		(pin "F26"
		)
		(pin "J31"
		)
		(pin "T30"
		)
		(pin "AD34"
		)
		(pin "AA27"
		)
		(pin "R17"
		)
		(pin "W13"
		)
		(pin "M26"
		)
		(pin "C9"
		)
		(pin "AA41"
		)
		(pin "AC27"
		)
		(pin "K2"
		)
		(pin "AB20"
		)
		(pin "R7"
		)
		(pin "N39"
		)
		(pin "D6"
		)
		(pin "M22"
		)
		(pin "M2"
		)
		(pin "AC9"
		)
		(pin "A3"
		)
		(pin "P2"
		)
		(pin "AA33"
		)
		(pin "A23"
		)
		(pin "E35"
		)
		(pin "U3"
		)
		(pin "V36"
		)
		(pin "K42"
		)
		(pin "R41"
		)
		(pin "R1"
		)
		(pin "AD22"
		)
		(pin "W7"
		)
		(pin "AB18"
		)
		(pin "E19"
		)
		(pin "AB12"
		)
		(pin "AD28"
		)
		(pin "AD40"
		)
		(pin "J1"
		)
		(pin "Y6"
		)
		(pin "Y8"
		)
		(pin "H36"
		)
		(pin "C13"
		)
		(pin "C23"
		)
		(pin "Y38"
		)
		(pin "U21"
		)
		(pin "F32"
		)
		(pin "F34"
		)
		(pin "A25"
		)
		(pin "N23"
		)
		(pin "W41"
		)
		(pin "AC31"
		)
		(pin "D12"
		)
		(pin "K34"
		)
		(pin "AA23"
		)
		(pin "AC17"
		)
		(pin "V22"
		)
		(pin "AA39"
		)
		(pin "J41"
		)
		(pin "V14"
		)
		(pin "U23"
		)
		(pin "V16"
		)
		(pin "W35"
		)
		(pin "AC21"
		)
		(pin "D32"
		)
		(pin "L1"
		)
		(pin "P24"
		)
		(pin "J3"
		)
		(pin "AC41"
		)
		(pin "AD14"
		)
		(pin "K22"
		)
		(pin "A11"
		)
		(pin "AA15"
		)
		(pin "F2"
		)
		(pin "A9"
		)
		(pin "N27"
		)
		(pin "C19"
		)
		(pin "K30"
		)
		(pin "L23"
		)
		(pin "N41"
		)
		(pin "F20"
		)
		(pin "AB28"
		)
		(pin "AD12"
		)
		(pin "C21"
		)
		(pin "U9"
		)
		(pin "V20"
		)
		(pin "D20"
		)
		(pin "L21"
		)
		(pin "R15"
		)
		(pin "K4"
		)
		(pin "N1"
		)
		(pin "H12"
		)
		(pin "J23"
		)
		(pin "J5"
		)
		(pin "E9"
		)
		(pin "M28"
		)
		(pin "U1"
		)
		(pin "Y2"
		)
		(pin "G5"
		)
		(pin "K20"
		)
		(pin "M18"
		)
		(pin "V2"
		)
		(pin "AC39"
		)
		(pin "T32"
		)
		(pin "E25"
		)
		(pin "AD38"
		)
		(pin "H26"
		)
		(pin "AA31"
		)
		(pin "G31"
		)
		(pin "U27"
		)
		(pin "U17"
		)
		(pin "C11"
		)
		(pin "N3"
		)
		(pin "A37"
		)
		(pin "F6"
		)
		(pin "Y30"
		)
		(pin "U7"
		)
		(pin "G15"
		)
		(pin "C29"
		)
		(pin "E39"
		)
		(pin "A35"
		)
		(pin "L3"
		)
		(pin "N25"
		)
		(pin "R25"
		)
		(pin "J37"
		)
		(pin "H42"
		)
		(pin "AD24"
		)
		(pin "B14"
		)
		(pin "P6"
		)
		(pin "R31"
		)
		(pin "A5"
		)
		(pin "D14"
		)
		(pin "AB10"
		)
		(pin "B18"
		)
		(pin "A27"
		)
		(pin "T40"
		)
		(pin "AB40"
		)
		(pin "P4"
		)
		(pin "AA35"
		)
		(pin "F36"
		)
		(pin "K18"
		)
		(pin "K38"
		)
		(pin "N33"
		)
		(pin "Y26"
		)
		(pin "Y28"
		)
		(pin "G21"
		)
		(pin "AA1"
		)
		(pin "AB2"
		)
		(pin "V38"
		)
		(pin "J9"
		)
		(pin "B6"
		)
		(pin "L35"
		)
		(pin "N7"
		)
		(pin "AC1"
		)
		(pin "E23"
		)
		(pin "F40"
		)
		(pin "F42"
		)
		(pin "P36"
		)
		(pin "F4"
		)
		(pin "AD16"
		)
		(pin "R11"
		)
		(pin "R27"
		)
		(pin "J13"
		)
		(pin "V34"
		)
		(pin "M10"
		)
		(pin "Y4"
		)
		(pin "Y40"
		)
		(pin "L27"
		)
		(pin "L9"
		)
		(pin "K10"
		)
		(pin "L39"
		)
		(pin "U5"
		)
		(pin "AB42"
		)
		(pin "R5"
		)
		(pin "G23"
		)
		(pin "M8"
		)
		(pin "AD8"
		)
		(pin "M16"
		)
		(pin "M12"
		)
		(pin "E3"
		)
		(pin "B12"
		)
		(pin "R23"
		)
		(pin "W25"
		)
		(pin "H4"
		)
		(pin "F8"
		)
		(pin "AC23"
		)
		(pin "AA3"
		)
		(pin "B10"
		)
		(pin "E31"
		)
		(pin "E33"
		)
		(pin "G1"
		)
		(pin "F18"
		)
		(pin "W17"
		)
		(pin "K36"
		)
		(pin "AB26"
		)
		(pin "R13"
		)
		(pin "AB32"
		)
		(pin "V18"
		)
		(pin "D16"
		)
		(pin "AA37"
		)
		(pin "C31"
		)
		(pin "C41"
		)
		(pin "A41"
		)
		(pin "E1"
		)
		(pin "P38"
		)
		(pin "U19"
		)
		(pin "R29"
		)
		(pin "E37"
		)
		(pin "E29"
		)
		(pin "A21"
		)
		(pin "A31"
		)
		(pin "U29"
		)
		(pin "AB34"
		)
		(pin "E17"
		)
		(pin "W15"
		)
		(pin "H40"
		)
		(pin "M24"
		)
		(pin "U15"
		)
		(pin "H2"
		)
		(pin "N21"
		)
		(pin "W33"
		)
		(pin "J29"
		)
		(pin "T42"
		)
		(pin "A13"
		)
		(pin "AD26"
		)
		(pin "P28"
		)
		(pin "T24"
		)
		(pin "F12"
		)
		(pin "AD2"
		)
		(pin "H34"
		)
		(pin "J33"
		)
		(pin "P40"
		)
		(pin "C17"
		)
		(pin "W19"
		)
		(pin "M6"
		)
		(pin "H6"
		)
		(pin "M40"
		)
		(pin "D30"
		)
		(pin "F10"
		)
		(pin "Y14"
		)
		(pin "L29"
		)
		(pin "P22"
		)
		(pin "W1"
		)
		(pin "V28"
		)
		(pin "E11"
		)
		(pin "J25"
		)
		(pin "G27"
		)
		(pin "M34"
		)
		(pin "Y18"
		)
		(pin "K8"
		)
		(pin "AC35"
		)
		(pin "AD36"
		)
		(pin "G19"
		)
		(pin "G41"
		)
		(pin "W3"
		)
		(pin "C37"
		)
		(pin "C27"
		)
		(pin "Y22"
		)
		(pin "C35"
		)
		(pin "L41"
		)
		(pin "P30"
		)
		(pin "V8"
		)
		(pin "AB30"
		)
		(pin "A29"
		)
		(pin "B22"
		)
		(pin "B32"
		)
		(pin "T36"
		)
		(pin "AA17"
		)
		(pin "K12"
		)
		(pin "P8"
		)
		(pin "T22"
		)
		(pin "C15"
		)
		(pin "W9"
		)
		(pin "W11"
		)
		(pin "P42"
		)
		(pin "T6"
		)
		(pin "B40"
		)
		(pin "N9"
		)
		(pin "K6"
		)
		(pin "A33"
		)
		(pin "T38"
		)
		(pin "J35"
		)
		(pin "E41"
		)
		(pin "T2"
		)
		(pin "C3"
		)
		(pin "R3"
		)
		(pin "D8"
		)
		(pin "F28"
		)
		(pin "F30"
		)
		(pin "Y32"
		)
		(pin "Y36"
		)
		(pin "AC25"
		)
		(pin "T4"
		)
		(pin "V26"
		)
		(pin "B16"
		)
		(pin "V32"
		)
		(pin "H10"
		)
		(pin "A7"
		)
		(pin "R9"
		)
		(pin "N11"
		)
		(pin "R37"
		)
		(pin "W37"
		)
		(pin "V4"
		)
		(pin "T14"
		)
		(pin "T16"
		)
		(pin "J21"
		)
		(pin "AB14"
		)
		(pin "J17"
		)
		(pin "W5"
		)
		(pin "D34"
		)
		(pin "Y34"
		)
		(pin "M36"
		)
		(pin "AA25"
		)
		(pin "B4"
		)
		(pin "AA29"
		)
		(pin "K16"
		)
		(pin "V40"
		)
		(pin "AC37"
		)
		(pin "AB24"
		)
		(pin "AD18"
		)
		(pin "AA7"
		)
		(pin "V12"
		)
		(pin "AC13"
		)
		(pin "T8"
		)
		(pin "E21"
		)
		(pin "A19"
		)
		(pin "E27"
		)
		(pin "K14"
		)
		(pin "AA13"
		)
		(pin "P16"
		)
		(pin "P18"
		)
		(pin "H30"
		)
		(pin "N31"
		)
		(pin "P12"
		)
		(pin "P14"
		)
		(pin "B42"
		)
		(pin "G25"
		)
		(pin "U25"
		)
		(pin "A39"
		)
		(pin "J11"
		)
		(pin "G11"
		)
		(pin "G29"
		)
		(pin "R19"
		)
		(pin "AC11"
		)
		(pin "F22"
		)
		(pin "W39"
		)
		(pin "AA9"
		)
		(pin "AB38"
		)
		(pin "L31"
		)
		(pin "T34"
		)
		(pin "J39"
		)
		(pin "F14"
		)
		(pin "H24"
		)
		(pin "G35"
		)
		(pin "W21"
		)
		(pin "K40"
		)
		(pin "N19"
		)
		(pin "B20"
		)
		(pin "U31"
		)
		(pin "R21"
		)
		(pin "R39"
		)
		(pin "P20"
		)
		(pin "R35"
		)
		(pin "AD42"
		)
		(pin "K24"
		)
		(pin "AB4"
		)
		(pin "AC33"
		)
		(pin "B8"
		)
		(pin "U33"
		)
		(pin "H32"
		)
		(pin "L33"
		)
		(pin "J19"
		)
		(pin "U13"
		)
		(pin "C39"
		)
		(pin "H22"
		)
		(pin "AD10"
		)
		(pin "Y20"
		)
		(pin "E15"
		)
		(pin "AA21"
		)
		(pin "K26"
		)
		(pin "C25"
		)
		(pin "M42"
		)
		(pin "U41"
		)
		(pin "Y16"
		)
		(pin "D28"
		)
		(pin "D36"
		)
		(pin "Y10"
		)
		(pin "AC19"
		)
		(pin "AB8"
		)
		(pin "AB36"
		)
		(pin "P26"
		)
		(pin "D38"
		)
		(pin "D40"
		)
		(pin "AA19"
		)
		(pin "E13"
		)
		(pin "A15"
		)
		(pin "H20"
		)
		(pin "K28"
		)
		(pin "F16"
		)
		(pin "W27"
		)
		(pin "D42"
		)
		(pin "AB6"
		)
		(pin "M14"
		)
		(pin "M32"
		)
		(pin "N5"
		)
		(pin "U11"
		)
		(pin "J27"
		)
		(pin "M30"
		)
		(pin "C33"
		)
		(pin "C7"
		)
		(pin "L15"
		)
		(pin "G33"
		)
		(pin "L19"
		)
		(pin "L17"
		)
		(pin "L5"
		)
		(pin "L25"
		)
		(pin "M38"
		)
		(pin "T18"
		)
		(pin "T20"
		)
		(pin "H18"
		)
		(pin "G7"
		)
		(pin "B36"
		)
		(pin "U39"
		)
		(pin "G39"
		)
		(pin "D2"
		)
		(pin "R33"
		)
		(pin "L11"
		)
		(pin "AC3"
		)
		(pin "AA11"
		)
		(pin "H38"
		)
		(pin "N13"
		)
		(pin "L13"
		)
		(pin "L7"
		)
		(pin "Y42"
		)
		(instances
			(project "OCuLink to 10GbE adapter"
				(path ""
					(reference "U9")
					(unit 6)
				)
			)
		)
	)
	(symbol
		(lib_id "antmicroTestPoints:TP_0.75mm_SMD")
		(at 92.71 53.34 180)
		(unit 1)
		(exclude_from_sim no)
		(in_bom no)
		(on_board yes)
		(dnp no)
		(property "Reference" "TP2"
			(at 88.392 53.34 0)
			(effects
				(font
					(size 1.27 1.27)
					(thickness 0.15)
				)
				(justify left)
			)
		)
		(property "Value" "TP_0.75mm_SMD"
			(at 82.55 49.53 0)
			(effects
				(font
					(size 1.27 1.27)
					(thickness 0.15)
				)
				(justify left bottom)
				(hide yes)
			)
		)
		(property "Footprint" "antmicro-footprints:TP_SMD_0.75mm"
			(at 82.55 46.99 0)
			(effects
				(font
					(size 1.27 1.27)
					(thickness 0.15)
				)
				(justify left bottom)
				(hide yes)
			)
		)
		(property "Datasheet" ""
			(at 74.93 40.64 0)
			(effects
				(font
					(size 1.27 1.27)
					(thickness 0.15)
				)
				(justify left bottom)
				(hide yes)
			)
		)
		(property "Description" "SMT test point"
			(at 92.71 53.34 0)
			(effects
				(font
					(size 1.27 1.27)
				)
				(hide yes)
			)
		)
		(property "MPN" ""
			(at 81.915 41.91 0)
			(effects
				(font
					(size 1.27 1.27)
					(thickness 0.15)
				)
				(justify left bottom)
				(hide yes)
			)
		)
		(property "Manufacturer" ""
			(at 81.915 46.99 0)
			(effects
				(font
					(size 1.27 1.27)
					(thickness 0.15)
				)
				(justify left bottom)
				(hide yes)
			)
		)
		(property "Author" "Antmicro"
			(at 82.55 44.45 0)
			(effects
				(font
					(size 1.27 1.27)
					(thickness 0.15)
				)
				(justify left bottom)
				(hide yes)
			)
		)
		(property "License" "Apache-2.0"
			(at 82.55 41.91 0)
			(effects
				(font
					(size 1.27 1.27)
					(thickness 0.15)
				)
				(justify left bottom)
				(hide yes)
			)
		)
		(pin "1"
		)
		(instances
			(project "OCuLink to 10GbE adapter"
				(path ""
					(reference "TP2")
					(unit 1)
				)
			)
		)
	)
	(symbol
		(lib_id "antmicroCapacitors0402:C_100n_0402")
		(at 96.52 220.98 90)
		(unit 1)
		(exclude_from_sim no)
		(in_bom yes)
		(on_board yes)
		(dnp no)
		(property "Reference" "C74"
			(at 98.552 217.17 90)
			(effects
				(font
					(size 1.27 1.27)
					(thickness 0.15)
				)
				(justify right)
			)
		)
		(property "Value" "C_100n_0402"
			(at 119.38 205.74 0)
			(effects
				(font
					(size 1.27 1.27)
					(thickness 0.15)
				)
				(justify left bottom)
				(hide yes)
			)
		)
		(property "Footprint" "antmicro-footprints:C_0402_1005Metric"
			(at 121.92 205.74 0)
			(effects
				(font
					(size 1.27 1.27)
					(thickness 0.15)
				)
				(justify left bottom)
				(hide yes)
			)
		)
		(property "Datasheet" "https://www.murata.com/products/productdetail?partno=GRM155R61H104KE14%23"
			(at 124.46 205.74 0)
			(effects
				(font
					(size 1.27 1.27)
					(thickness 0.15)
				)
				(justify left bottom)
				(hide yes)
			)
		)
		(property "Description" "SMD Multilayer Ceramic Capacitor, 0.1 µF, 50 V, 0402 [1005 Metric], ± 10%, X5R, GRM Series"
			(at 96.52 220.98 0)
			(effects
				(font
					(size 1.27 1.27)
				)
				(hide yes)
			)
		)
		(property "MPN" "GRM155R61H104KE14D"
			(at 127 205.74 0)
			(effects
				(font
					(size 1.27 1.27)
					(thickness 0.15)
				)
				(justify left bottom)
				(hide yes)
			)
		)
		(property "Val" "100n"
			(at 98.552 219.71 90)
			(effects
				(font
					(size 1.27 1.27)
					(thickness 0.15)
				)
				(justify right)
			)
		)
		(property "Voltage" "50V"
			(at 106.68 205.74 0)
			(effects
				(font
					(size 1.27 1.27)
					(thickness 0.15)
				)
				(justify left bottom)
				(hide yes)
			)
		)
		(property "Dielectric" "X5R"
			(at 109.22 205.74 0)
			(effects
				(font
					(size 1.27 1.27)
					(thickness 0.15)
				)
				(justify left bottom)
				(hide yes)
			)
		)
		(property "Manufacturer" "Murata"
			(at 111.76 205.74 0)
			(effects
				(font
					(size 1.27 1.27)
					(thickness 0.15)
				)
				(justify left bottom)
				(hide yes)
			)
		)
		(property "License" "Apache-2.0"
			(at 114.3 205.74 0)
			(effects
				(font
					(size 1.27 1.27)
					(thickness 0.15)
				)
				(justify left bottom)
				(hide yes)
			)
		)
		(property "Author" "Antmicro"
			(at 116.84 205.74 0)
			(effects
				(font
					(size 1.27 1.27)
					(thickness 0.15)
				)
				(justify left bottom)
				(hide yes)
			)
		)
		(pin "2"
		)
		(pin "1"
		)
		(instances
			(project "OCuLink to 10GbE adapter"
				(path ""
					(reference "C74")
					(unit 1)
				)
			)
		)
	)
	(symbol
		(lib_id "antmicroResistors0402:R_10k_0402")
		(at 127 104.14 90)
		(unit 1)
		(exclude_from_sim no)
		(in_bom no)
		(on_board yes)
		(dnp yes)
		(property "Reference" "R97"
			(at 128.27 100.33 90)
			(effects
				(font
					(size 1.27 1.27)
					(thickness 0.15)
				)
				(justify right)
			)
		)
		(property "Value" "R_10k_0402"
			(at 139.7 83.82 0)
			(effects
				(font
					(size 1.27 1.27)
					(thickness 0.15)
				)
				(justify left bottom)
				(hide yes)
			)
		)
		(property "Footprint" "antmicro-footprints:R_0402_1005Metric"
			(at 142.24 83.82 0)
			(effects
				(font
					(size 1.27 1.27)
					(thickness 0.15)
				)
				(justify left bottom)
				(hide yes)
			)
		)
		(property "Datasheet" "https://www.bourns.com/docs/product-datasheets/cr.pdf"
			(at 144.78 83.82 0)
			(effects
				(font
					(size 1.27 1.27)
					(thickness 0.15)
				)
				(justify left bottom)
				(hide yes)
			)
		)
		(property "Description" "SMD Chip Resistor, 10 kohm, ± 1%, 62.5 mW, 0402 [1005 Metric], Thick Film, General Purpose"
			(at 127 104.14 0)
			(effects
				(font
					(size 1.27 1.27)
				)
				(hide yes)
			)
		)
		(property "MPN" "CR0402-FX-1002GLF"
			(at 147.32 83.82 0)
			(effects
				(font
					(size 1.27 1.27)
					(thickness 0.15)
				)
				(justify left bottom)
				(hide yes)
			)
		)
		(property "Manufacturer" "Bourns"
			(at 149.86 83.82 0)
			(effects
				(font
					(size 1.27 1.27)
					(thickness 0.15)
				)
				(justify left bottom)
				(hide yes)
			)
		)
		(property "License" "Apache-2.0"
			(at 152.4 83.82 0)
			(effects
				(font
					(size 1.27 1.27)
					(thickness 0.15)
				)
				(justify left bottom)
				(hide yes)
			)
		)
		(property "Author" "Antmicro"
			(at 154.94 83.82 0)
			(effects
				(font
					(size 1.27 1.27)
					(thickness 0.15)
				)
				(justify left bottom)
				(hide yes)
			)
		)
		(property "Val" "10k"
			(at 128.27 102.87 90)
			(effects
				(font
					(size 1.27 1.27)
					(thickness 0.15)
				)
				(justify right)
			)
		)
		(property "Tolerance" "1%"
			(at 137.16 83.82 0)
			(effects
				(font
					(size 1.27 1.27)
				)
				(justify left bottom)
				(hide yes)
			)
		)
		(pin "2"
		)
		(pin "1"
		)
		(instances
			(project "OCuLink to 10GbE adapter"
				(path ""
					(reference "R97")
					(unit 1)
				)
			)
		)
	)
	(symbol
		(lib_id "antmicroResistors0402:R_10k_0402")
		(at 247.65 96.52 90)
		(unit 1)
		(exclude_from_sim no)
		(in_bom yes)
		(on_board yes)
		(dnp no)
		(property "Reference" "R91"
			(at 249.174 92.71 90)
			(effects
				(font
					(size 1.27 1.27)
					(thickness 0.15)
				)
				(justify right)
			)
		)
		(property "Value" "R_10k_0402"
			(at 260.35 76.2 0)
			(effects
				(font
					(size 1.27 1.27)
					(thickness 0.15)
				)
				(justify left bottom)
				(hide yes)
			)
		)
		(property "Footprint" "antmicro-footprints:R_0402_1005Metric"
			(at 262.89 76.2 0)
			(effects
				(font
					(size 1.27 1.27)
					(thickness 0.15)
				)
				(justify left bottom)
				(hide yes)
			)
		)
		(property "Datasheet" "https://www.bourns.com/docs/product-datasheets/cr.pdf"
			(at 265.43 76.2 0)
			(effects
				(font
					(size 1.27 1.27)
					(thickness 0.15)
				)
				(justify left bottom)
				(hide yes)
			)
		)
		(property "Description" "SMD Chip Resistor, 10 kohm, ± 1%, 62.5 mW, 0402 [1005 Metric], Thick Film, General Purpose"
			(at 247.65 96.52 0)
			(effects
				(font
					(size 1.27 1.27)
				)
				(hide yes)
			)
		)
		(property "MPN" "CR0402-FX-1002GLF"
			(at 267.97 76.2 0)
			(effects
				(font
					(size 1.27 1.27)
					(thickness 0.15)
				)
				(justify left bottom)
				(hide yes)
			)
		)
		(property "Manufacturer" "Bourns"
			(at 270.51 76.2 0)
			(effects
				(font
					(size 1.27 1.27)
					(thickness 0.15)
				)
				(justify left bottom)
				(hide yes)
			)
		)
		(property "License" "Apache-2.0"
			(at 273.05 76.2 0)
			(effects
				(font
					(size 1.27 1.27)
					(thickness 0.15)
				)
				(justify left bottom)
				(hide yes)
			)
		)
		(property "Author" "Antmicro"
			(at 275.59 76.2 0)
			(effects
				(font
					(size 1.27 1.27)
					(thickness 0.15)
				)
				(justify left bottom)
				(hide yes)
			)
		)
		(property "Val" "10k"
			(at 249.174 95.25 90)
			(effects
				(font
					(size 1.27 1.27)
					(thickness 0.15)
				)
				(justify right)
			)
		)
		(property "Tolerance" "1%"
			(at 257.81 76.2 0)
			(effects
				(font
					(size 1.27 1.27)
				)
				(justify left bottom)
				(hide yes)
			)
		)
		(pin "2"
		)
		(pin "1"
		)
		(instances
			(project "OCuLink to 10GbE adapter"
				(path ""
					(reference "R91")
					(unit 1)
				)
			)
		)
	)
	(symbol
		(lib_id "antmicroResistors0402:R_22R_0402")
		(at 153.67 66.04 0)
		(unit 1)
		(exclude_from_sim no)
		(in_bom yes)
		(on_board yes)
		(dnp no)
		(property "Reference" "R85"
			(at 153.67 64.77 0)
			(effects
				(font
					(size 1.27 1.27)
					(thickness 0.15)
				)
				(justify right)
			)
		)
		(property "Value" "R_22R_0402"
			(at 173.99 78.74 0)
			(effects
				(font
					(size 1.27 1.27)
					(thickness 0.15)
				)
				(justify left bottom)
				(hide yes)
			)
		)
		(property "Footprint" "antmicro-footprints:R_0402_1005Metric"
			(at 173.99 81.28 0)
			(effects
				(font
					(size 1.27 1.27)
					(thickness 0.15)
				)
				(justify left bottom)
				(hide yes)
			)
		)
		(property "Datasheet" "https://www.bourns.com/docs/product-datasheets/cr.pdf"
			(at 173.99 83.82 0)
			(effects
				(font
					(size 1.27 1.27)
					(thickness 0.15)
				)
				(justify left bottom)
				(hide yes)
			)
		)
		(property "Description" "SMD Chip Resistor, 22 ohm, ± 1%, 62.5 mW, 0402 [1005 Metric], Thick Film, General Purpose"
			(at 153.67 66.04 0)
			(effects
				(font
					(size 1.27 1.27)
				)
				(hide yes)
			)
		)
		(property "MPN" "CR0402-FX-22R0GLF"
			(at 173.99 86.36 0)
			(effects
				(font
					(size 1.27 1.27)
					(thickness 0.15)
				)
				(justify left bottom)
				(hide yes)
			)
		)
		(property "Manufacturer" "Bourns"
			(at 173.99 88.9 0)
			(effects
				(font
					(size 1.27 1.27)
					(thickness 0.15)
				)
				(justify left bottom)
				(hide yes)
			)
		)
		(property "License" "Apache-2.0"
			(at 173.99 91.44 0)
			(effects
				(font
					(size 1.27 1.27)
					(thickness 0.15)
				)
				(justify left bottom)
				(hide yes)
			)
		)
		(property "Author" "Antmicro"
			(at 173.99 93.98 0)
			(effects
				(font
					(size 1.27 1.27)
					(thickness 0.15)
				)
				(justify left bottom)
				(hide yes)
			)
		)
		(property "Val" "22R"
			(at 158.75 64.77 0)
			(effects
				(font
					(size 1.27 1.27)
					(thickness 0.15)
				)
				(justify left)
			)
		)
		(property "Tolerance" "1%"
			(at 173.99 76.2 0)
			(effects
				(font
					(size 1.27 1.27)
				)
				(justify left bottom)
				(hide yes)
			)
		)
		(pin "2"
		)
		(pin "1"
		)
		(instances
			(project "OCuLink to 10GbE adapter"
				(path ""
					(reference "R85")
					(unit 1)
				)
			)
		)
	)
	(symbol
		(lib_id "antmicroResistors0402:R_100R_0402")
		(at 124.46 129.54 90)
		(unit 1)
		(exclude_from_sim no)
		(in_bom yes)
		(on_board yes)
		(dnp no)
		(property "Reference" "R106"
			(at 125.984 125.73 90)
			(effects
				(font
					(size 1.27 1.27)
					(thickness 0.15)
				)
				(justify right)
			)
		)
		(property "Value" "R_100R_0402"
			(at 137.16 109.22 0)
			(effects
				(font
					(size 1.27 1.27)
					(thickness 0.15)
				)
				(justify left bottom)
				(hide yes)
			)
		)
		(property "Footprint" "antmicro-footprints:R_0402_1005Metric"
			(at 139.7 109.22 0)
			(effects
				(font
					(size 1.27 1.27)
					(thickness 0.15)
				)
				(justify left bottom)
				(hide yes)
			)
		)
		(property "Datasheet" "https://www.bourns.com/docs/product-datasheets/cr.pdf"
			(at 142.24 109.22 0)
			(effects
				(font
					(size 1.27 1.27)
					(thickness 0.15)
				)
				(justify left bottom)
				(hide yes)
			)
		)
		(property "Description" "SMD Chip Resistor, 100 ohm, ± 1%, 62.5 mW, 0402 [1005 Metric], Thick Film, General Purpose"
			(at 124.46 129.54 0)
			(effects
				(font
					(size 1.27 1.27)
				)
				(hide yes)
			)
		)
		(property "MPN" "CR0402-FX-1000GLF"
			(at 144.78 109.22 0)
			(effects
				(font
					(size 1.27 1.27)
					(thickness 0.15)
				)
				(justify left bottom)
				(hide yes)
			)
		)
		(property "Manufacturer" "Bourns"
			(at 147.32 109.22 0)
			(effects
				(font
					(size 1.27 1.27)
					(thickness 0.15)
				)
				(justify left bottom)
				(hide yes)
			)
		)
		(property "License" "Apache-2.0"
			(at 149.86 109.22 0)
			(effects
				(font
					(size 1.27 1.27)
					(thickness 0.15)
				)
				(justify left bottom)
				(hide yes)
			)
		)
		(property "Author" "Antmicro"
			(at 152.4 109.22 0)
			(effects
				(font
					(size 1.27 1.27)
					(thickness 0.15)
				)
				(justify left bottom)
				(hide yes)
			)
		)
		(property "Val" "100R"
			(at 125.984 128.27 90)
			(effects
				(font
					(size 1.27 1.27)
					(thickness 0.15)
				)
				(justify right)
			)
		)
		(property "Tolerance" "1%"
			(at 134.62 109.22 0)
			(effects
				(font
					(size 1.27 1.27)
				)
				(justify left bottom)
				(hide yes)
			)
		)
		(pin "2"
		)
		(pin "1"
		)
		(instances
			(project "OCuLink to 10GbE adapter"
				(path ""
					(reference "R106")
					(unit 1)
				)
			)
		)
	)
	(symbol
		(lib_id "antmicroResistors0402:R_100R_0402")
		(at 58.42 232.41 0)
		(unit 1)
		(exclude_from_sim no)
		(in_bom yes)
		(on_board yes)
		(dnp no)
		(property "Reference" "R50"
			(at 58.42 231.14 0)
			(effects
				(font
					(size 1.27 1.27)
					(thickness 0.15)
				)
				(justify right)
			)
		)
		(property "Value" "R_100R_0402"
			(at 78.74 245.11 0)
			(effects
				(font
					(size 1.27 1.27)
					(thickness 0.15)
				)
				(justify left bottom)
				(hide yes)
			)
		)
		(property "Footprint" "antmicro-footprints:R_0402_1005Metric"
			(at 78.74 247.65 0)
			(effects
				(font
					(size 1.27 1.27)
					(thickness 0.15)
				)
				(justify left bottom)
				(hide yes)
			)
		)
		(property "Datasheet" "https://www.bourns.com/docs/product-datasheets/cr.pdf"
			(at 78.74 250.19 0)
			(effects
				(font
					(size 1.27 1.27)
					(thickness 0.15)
				)
				(justify left bottom)
				(hide yes)
			)
		)
		(property "Description" "SMD Chip Resistor, 100 ohm, ± 1%, 62.5 mW, 0402 [1005 Metric], Thick Film, General Purpose"
			(at 78.74 262.89 0)
			(effects
				(font
					(size 1.27 1.27)
				)
				(justify left bottom)
				(hide yes)
			)
		)
		(property "MPN" "CR0402-FX-1000GLF"
			(at 78.74 252.73 0)
			(effects
				(font
					(size 1.27 1.27)
					(thickness 0.15)
				)
				(justify left bottom)
				(hide yes)
			)
		)
		(property "Manufacturer" "Bourns"
			(at 78.74 255.27 0)
			(effects
				(font
					(size 1.27 1.27)
					(thickness 0.15)
				)
				(justify left bottom)
				(hide yes)
			)
		)
		(property "License" "Apache-2.0"
			(at 78.74 257.81 0)
			(effects
				(font
					(size 1.27 1.27)
					(thickness 0.15)
				)
				(justify left bottom)
				(hide yes)
			)
		)
		(property "Author" "Antmicro"
			(at 78.74 260.35 0)
			(effects
				(font
					(size 1.27 1.27)
					(thickness 0.15)
				)
				(justify left bottom)
				(hide yes)
			)
		)
		(property "Val" "100R"
			(at 63.5 231.14 0)
			(effects
				(font
					(size 1.27 1.27)
					(thickness 0.15)
				)
				(justify left)
			)
		)
		(property "Tolerance" "1%"
			(at 78.74 242.57 0)
			(effects
				(font
					(size 1.27 1.27)
				)
				(justify left bottom)
				(hide yes)
			)
		)
		(pin "2"
		)
		(pin "1"
		)
		(instances
			(project "OCuLink to 10GbE adapter"
				(path ""
					(reference "R50")
					(unit 1)
				)
			)
		)
	)
	(symbol
		(lib_id "antmicroLogicBuffersDriversReceiversTransceivers:74LVC1G07_SOT-753")
		(at 44.45 118.11 0)
		(unit 1)
		(exclude_from_sim no)
		(in_bom yes)
		(on_board yes)
		(dnp no)
		(fields_autoplaced yes)
		(property "Reference" "U10"
			(at 52.07 110.49 0)
			(effects
				(font
					(size 1.27 1.27)
					(thickness 0.15)
				)
			)
		)
		(property "Value" "74LVC1G07_SOT-753"
			(at 74.93 118.11 0)
			(effects
				(font
					(size 1.27 1.27)
					(thickness 0.15)
				)
				(justify left bottom)
				(hide yes)
			)
		)
		(property "Footprint" "antmicro-footprints:SOT-753"
			(at 74.93 120.65 0)
			(effects
				(font
					(size 1.27 1.27)
					(thickness 0.15)
				)
				(justify left bottom)
				(hide yes)
			)
		)
		(property "Datasheet" "https://www.mouser.com/datasheet/2/916/74LVC1G07-1529858.pdf"
			(at 74.93 123.19 0)
			(effects
				(font
					(size 1.27 1.27)
					(thickness 0.15)
				)
				(justify left bottom)
				(hide yes)
			)
		)
		(property "Description" "Buffer, 74LVC1G07, 1.65 V to 5.5 V, SC-74A-5"
			(at 44.45 118.11 0)
			(effects
				(font
					(size 1.27 1.27)
				)
				(hide yes)
			)
		)
		(property "MPN" "74LVC1G07GV,125"
			(at 52.07 113.03 0)
			(effects
				(font
					(size 1.27 1.27)
					(thickness 0.15)
				)
			)
		)
		(property "Manufacturer" "Nexperia"
			(at 74.93 128.27 0)
			(effects
				(font
					(size 1.27 1.27)
					(thickness 0.15)
				)
				(justify left bottom)
				(hide yes)
			)
		)
		(property "Author" "Antmicro"
			(at 74.93 130.81 0)
			(effects
				(font
					(size 1.27 1.27)
					(thickness 0.15)
				)
				(justify left bottom)
				(hide yes)
			)
		)
		(property "License" "Apache-2.0"
			(at 74.93 133.35 0)
			(effects
				(font
					(size 1.27 1.27)
					(thickness 0.15)
				)
				(justify left bottom)
				(hide yes)
			)
		)
		(pin "4"
		)
		(pin "5"
		)
		(pin "2"
		)
		(pin "1"
		)
		(pin "3"
		)
		(instances
			(project ""
				(path ""
					(reference "U10")
					(unit 1)
				)
			)
		)
	)
	(symbol
		(lib_id "antmicroResistors0402:R_1k_0402")
		(at 132.08 243.84 90)
		(unit 1)
		(exclude_from_sim no)
		(in_bom yes)
		(on_board yes)
		(dnp no)
		(property "Reference" "R119"
			(at 133.604 240.03 90)
			(effects
				(font
					(size 1.27 1.27)
					(thickness 0.15)
				)
				(justify right)
			)
		)
		(property "Value" "R_1k_0402"
			(at 144.78 223.52 0)
			(effects
				(font
					(size 1.27 1.27)
					(thickness 0.15)
				)
				(justify left bottom)
				(hide yes)
			)
		)
		(property "Footprint" "antmicro-footprints:R_0402_1005Metric"
			(at 147.32 223.52 0)
			(effects
				(font
					(size 1.27 1.27)
					(thickness 0.15)
				)
				(justify left bottom)
				(hide yes)
			)
		)
		(property "Datasheet" "https://www.bourns.com/docs/product-datasheets/cr.pdf"
			(at 149.86 223.52 0)
			(effects
				(font
					(size 1.27 1.27)
					(thickness 0.15)
				)
				(justify left bottom)
				(hide yes)
			)
		)
		(property "Description" "SMD Chip Resistor, 1 kohm, ± 1%, 63 mW, 0402 [1005 Metric], Thick Film, General Purpose"
			(at 132.08 243.84 0)
			(effects
				(font
					(size 1.27 1.27)
				)
				(hide yes)
			)
		)
		(property "MPN" "CR0402-FX-1001GLF"
			(at 152.4 223.52 0)
			(effects
				(font
					(size 1.27 1.27)
					(thickness 0.15)
				)
				(justify left bottom)
				(hide yes)
			)
		)
		(property "Manufacturer" "Bourns"
			(at 154.94 223.52 0)
			(effects
				(font
					(size 1.27 1.27)
					(thickness 0.15)
				)
				(justify left bottom)
				(hide yes)
			)
		)
		(property "License" "Apache-2.0"
			(at 157.48 223.52 0)
			(effects
				(font
					(size 1.27 1.27)
					(thickness 0.15)
				)
				(justify left bottom)
				(hide yes)
			)
		)
		(property "Author" "Antmicro"
			(at 160.02 223.52 0)
			(effects
				(font
					(size 1.27 1.27)
					(thickness 0.15)
				)
				(justify left bottom)
				(hide yes)
			)
		)
		(property "Val" "1k"
			(at 133.604 242.57 90)
			(effects
				(font
					(size 1.27 1.27)
					(thickness 0.15)
				)
				(justify right)
			)
		)
		(property "Tolerance" "1%"
			(at 142.24 223.52 0)
			(effects
				(font
					(size 1.27 1.27)
				)
				(justify left bottom)
				(hide yes)
			)
		)
		(pin "1"
		)
		(pin "2"
		)
		(instances
			(project "OCuLink to 10GbE adapter"
				(path ""
					(reference "R119")
					(unit 1)
				)
			)
		)
	)
	(symbol
		(lib_id "antmicropower:GND")
		(at 67.31 237.49 0)
		(mirror y)
		(unit 1)
		(exclude_from_sim no)
		(in_bom yes)
		(on_board yes)
		(dnp no)
		(property "Reference" "#PWR0104"
			(at 58.42 240.03 0)
			(effects
				(font
					(size 1.27 1.27)
					(thickness 0.15)
				)
				(justify left bottom)
				(hide yes)
			)
		)
		(property "Value" "GND"
			(at 67.31 241.3 0)
			(effects
				(font
					(size 1.27 1.27)
					(thickness 0.15)
				)
			)
		)
		(property "Footprint" ""
			(at 58.42 245.11 0)
			(effects
				(font
					(size 1.27 1.27)
					(thickness 0.15)
				)
				(justify left bottom)
				(hide yes)
			)
		)
		(property "Datasheet" ""
			(at 58.42 250.19 0)
			(effects
				(font
					(size 1.27 1.27)
					(thickness 0.15)
				)
				(justify left bottom)
				(hide yes)
			)
		)
		(property "Description" ""
			(at 67.31 237.49 0)
			(effects
				(font
					(size 1.27 1.27)
				)
				(hide yes)
			)
		)
		(property "Author" "Antmicro"
			(at 58.42 245.11 0)
			(effects
				(font
					(size 1.27 1.27)
					(thickness 0.15)
				)
				(justify left bottom)
				(hide yes)
			)
		)
		(property "License" "Apache-2.0"
			(at 58.42 247.65 0)
			(effects
				(font
					(size 1.27 1.27)
					(thickness 0.15)
				)
				(justify left bottom)
				(hide yes)
			)
		)
		(pin "1"
		)
		(instances
			(project "OCuLink to 10GbE adapter"
				(path ""
					(reference "#PWR0104")
					(unit 1)
				)
			)
		)
	)
	(symbol
		(lib_id "antmicroCapacitors0402:C_1u_25V_0402")
		(at 114.3 129.54 90)
		(unit 1)
		(exclude_from_sim no)
		(in_bom yes)
		(on_board yes)
		(dnp no)
		(property "Reference" "C211"
			(at 116.332 125.73 90)
			(effects
				(font
					(size 1.27 1.27)
					(thickness 0.15)
				)
				(justify right)
			)
		)
		(property "Value" "C_1u_25V_0402"
			(at 124.46 109.22 0)
			(effects
				(font
					(size 1.27 1.27)
					(thickness 0.15)
				)
				(justify left bottom)
				(hide yes)
			)
		)
		(property "Footprint" "antmicro-footprints:C_0402_1005Metric"
			(at 127 109.22 0)
			(effects
				(font
					(size 1.27 1.27)
					(thickness 0.15)
				)
				(justify left bottom)
				(hide yes)
			)
		)
		(property "Datasheet" "https://www.murata.com/products/productdetail?partno=GRM155R61E105KE11%23"
			(at 129.54 109.22 0)
			(effects
				(font
					(size 1.27 1.27)
					(thickness 0.15)
				)
				(justify left bottom)
				(hide yes)
			)
		)
		(property "Description" "SMD Multilayer Ceramic Capacitor, 1 µF, 25 V, 0402 [1005 Metric], ± 10%, X5R, GRM Series"
			(at 114.3 129.54 0)
			(effects
				(font
					(size 1.27 1.27)
				)
				(hide yes)
			)
		)
		(property "MPN" "GRM155R61E105KE11J"
			(at 132.08 109.22 0)
			(effects
				(font
					(size 1.27 1.27)
					(thickness 0.15)
				)
				(justify left bottom)
				(hide yes)
			)
		)
		(property "Manufacturer" "Murata"
			(at 134.62 109.22 0)
			(effects
				(font
					(size 1.27 1.27)
					(thickness 0.15)
				)
				(justify left bottom)
				(hide yes)
			)
		)
		(property "License" "Apache-2.0"
			(at 137.16 109.22 0)
			(effects
				(font
					(size 1.27 1.27)
					(thickness 0.15)
				)
				(justify left bottom)
				(hide yes)
			)
		)
		(property "Author" "Antmicro"
			(at 139.7 109.22 0)
			(effects
				(font
					(size 1.27 1.27)
					(thickness 0.15)
				)
				(justify left bottom)
				(hide yes)
			)
		)
		(property "Val" "1u"
			(at 116.332 128.27 90)
			(effects
				(font
					(size 1.27 1.27)
					(thickness 0.15)
				)
				(justify right)
			)
		)
		(property "Voltage" "25V"
			(at 142.24 109.22 0)
			(effects
				(font
					(size 1.27 1.27)
				)
				(justify left bottom)
				(hide yes)
			)
		)
		(property "Dielectric" "X5R"
			(at 144.78 109.22 0)
			(effects
				(font
					(size 1.27 1.27)
				)
				(justify left bottom)
				(hide yes)
			)
		)
		(pin "2"
		)
		(pin "1"
		)
		(instances
			(project "oculink-to-10gbe-adapter"
				(path ""
					(reference "C211")
					(unit 1)
				)
			)
		)
	)
	(symbol
		(lib_id "antmicroResistors0402:R_2k_0402")
		(at 163.83 185.42 90)
		(unit 1)
		(exclude_from_sim no)
		(in_bom yes)
		(on_board yes)
		(dnp no)
		(property "Reference" "R115"
			(at 165.354 181.61 90)
			(effects
				(font
					(size 1.27 1.27)
					(thickness 0.15)
				)
				(justify right)
			)
		)
		(property "Value" "R_2k_0402"
			(at 176.53 165.1 0)
			(effects
				(font
					(size 1.27 1.27)
					(thickness 0.15)
				)
				(justify left bottom)
				(hide yes)
			)
		)
		(property "Footprint" "antmicro-footprints:R_0402_1005Metric"
			(at 179.07 165.1 0)
			(effects
				(font
					(size 1.27 1.27)
					(thickness 0.15)
				)
				(justify left bottom)
				(hide yes)
			)
		)
		(property "Datasheet" "https://www.bourns.com/docs/product-datasheets/cr.pdf"
			(at 181.61 165.1 0)
			(effects
				(font
					(size 1.27 1.27)
					(thickness 0.15)
				)
				(justify left bottom)
				(hide yes)
			)
		)
		(property "Description" "SMD Chip Resistor, 2 kohm, ± 1%, 62.5 mW, 0402 [1005 Metric], Thick Film, General Purpose"
			(at 163.83 185.42 0)
			(effects
				(font
					(size 1.27 1.27)
				)
				(hide yes)
			)
		)
		(property "MPN" "CR0402-FX-2001GLF"
			(at 184.15 165.1 0)
			(effects
				(font
					(size 1.27 1.27)
					(thickness 0.15)
				)
				(justify left bottom)
				(hide yes)
			)
		)
		(property "Manufacturer" "Bourns"
			(at 186.69 165.1 0)
			(effects
				(font
					(size 1.27 1.27)
					(thickness 0.15)
				)
				(justify left bottom)
				(hide yes)
			)
		)
		(property "License" "Apache-2.0"
			(at 189.23 165.1 0)
			(effects
				(font
					(size 1.27 1.27)
					(thickness 0.15)
				)
				(justify left bottom)
				(hide yes)
			)
		)
		(property "Author" "Antmicro"
			(at 191.77 165.1 0)
			(effects
				(font
					(size 1.27 1.27)
					(thickness 0.15)
				)
				(justify left bottom)
				(hide yes)
			)
		)
		(property "Val" "2k"
			(at 165.354 184.15 90)
			(effects
				(font
					(size 1.27 1.27)
					(thickness 0.15)
				)
				(justify right)
			)
		)
		(property "Tolerance" "1%"
			(at 173.99 165.1 0)
			(effects
				(font
					(size 1.27 1.27)
				)
				(justify left bottom)
				(hide yes)
			)
		)
		(pin "1"
		)
		(pin "2"
		)
		(instances
			(project "OCuLink to 10GbE adapter"
				(path ""
					(reference "R115")
					(unit 1)
				)
			)
		)
	)
	(symbol
		(lib_id "antmicropower:+3V3")
		(at 110.49 93.98 0)
		(unit 1)
		(exclude_from_sim no)
		(in_bom yes)
		(on_board yes)
		(dnp no)
		(property "Reference" "#PWR0264"
			(at 125.73 93.98 0)
			(effects
				(font
					(size 1.27 1.27)
					(thickness 0.15)
				)
				(justify left bottom)
				(hide yes)
			)
		)
		(property "Value" "+3V3"
			(at 110.49 90.17 0)
			(effects
				(font
					(size 1.27 1.27)
					(thickness 0.15)
				)
			)
		)
		(property "Footprint" ""
			(at 125.73 101.6 0)
			(effects
				(font
					(size 1.27 1.27)
					(thickness 0.15)
				)
				(justify left bottom)
				(hide yes)
			)
		)
		(property "Datasheet" ""
			(at 125.73 104.14 0)
			(effects
				(font
					(size 1.27 1.27)
					(thickness 0.15)
				)
				(justify left bottom)
				(hide yes)
			)
		)
		(property "Description" ""
			(at 110.49 93.98 0)
			(effects
				(font
					(size 1.27 1.27)
				)
				(hide yes)
			)
		)
		(property "Author" "Antmicro"
			(at 125.73 96.52 0)
			(effects
				(font
					(size 1.27 1.27)
					(thickness 0.15)
				)
				(justify left bottom)
				(hide yes)
			)
		)
		(property "License" "Apache-2.0"
			(at 125.73 99.06 0)
			(effects
				(font
					(size 1.27 1.27)
					(thickness 0.15)
				)
				(justify left bottom)
				(hide yes)
			)
		)
		(pin "1"
		)
		(instances
			(project "OCuLink to 10GbE adapter"
				(path ""
					(reference "#PWR0264")
					(unit 1)
				)
			)
		)
	)
	(symbol
		(lib_id "antmicroResistors0402:R_10k_0402")
		(at 148.59 78.74 90)
		(unit 1)
		(exclude_from_sim no)
		(in_bom yes)
		(on_board yes)
		(dnp no)
		(property "Reference" "R90"
			(at 150.114 74.93 90)
			(effects
				(font
					(size 1.27 1.27)
					(thickness 0.15)
				)
				(justify right)
			)
		)
		(property "Value" "R_10k_0402"
			(at 161.29 58.42 0)
			(effects
				(font
					(size 1.27 1.27)
					(thickness 0.15)
				)
				(justify left bottom)
				(hide yes)
			)
		)
		(property "Footprint" "antmicro-footprints:R_0402_1005Metric"
			(at 163.83 58.42 0)
			(effects
				(font
					(size 1.27 1.27)
					(thickness 0.15)
				)
				(justify left bottom)
				(hide yes)
			)
		)
		(property "Datasheet" "https://www.bourns.com/docs/product-datasheets/cr.pdf"
			(at 166.37 58.42 0)
			(effects
				(font
					(size 1.27 1.27)
					(thickness 0.15)
				)
				(justify left bottom)
				(hide yes)
			)
		)
		(property "Description" "SMD Chip Resistor, 10 kohm, ± 1%, 62.5 mW, 0402 [1005 Metric], Thick Film, General Purpose"
			(at 148.59 78.74 0)
			(effects
				(font
					(size 1.27 1.27)
				)
				(hide yes)
			)
		)
		(property "MPN" "CR0402-FX-1002GLF"
			(at 168.91 58.42 0)
			(effects
				(font
					(size 1.27 1.27)
					(thickness 0.15)
				)
				(justify left bottom)
				(hide yes)
			)
		)
		(property "Manufacturer" "Bourns"
			(at 171.45 58.42 0)
			(effects
				(font
					(size 1.27 1.27)
					(thickness 0.15)
				)
				(justify left bottom)
				(hide yes)
			)
		)
		(property "License" "Apache-2.0"
			(at 173.99 58.42 0)
			(effects
				(font
					(size 1.27 1.27)
					(thickness 0.15)
				)
				(justify left bottom)
				(hide yes)
			)
		)
		(property "Author" "Antmicro"
			(at 176.53 58.42 0)
			(effects
				(font
					(size 1.27 1.27)
					(thickness 0.15)
				)
				(justify left bottom)
				(hide yes)
			)
		)
		(property "Val" "10k"
			(at 150.114 77.47 90)
			(effects
				(font
					(size 1.27 1.27)
					(thickness 0.15)
				)
				(justify right)
			)
		)
		(property "Tolerance" "1%"
			(at 158.75 58.42 0)
			(effects
				(font
					(size 1.27 1.27)
				)
				(justify left bottom)
				(hide yes)
			)
		)
		(pin "2"
		)
		(pin "1"
		)
		(instances
			(project ""
				(path ""
					(reference "R90")
					(unit 1)
				)
			)
		)
	)
	(symbol
		(lib_id "antmicropower:GND")
		(at 97.79 181.61 0)
		(mirror y)
		(unit 1)
		(exclude_from_sim no)
		(in_bom yes)
		(on_board yes)
		(dnp no)
		(property "Reference" "#PWR0109"
			(at 88.9 184.15 0)
			(effects
				(font
					(size 1.27 1.27)
					(thickness 0.15)
				)
				(justify left bottom)
				(hide yes)
			)
		)
		(property "Value" "GND"
			(at 97.79 185.42 0)
			(effects
				(font
					(size 1.27 1.27)
					(thickness 0.15)
				)
			)
		)
		(property "Footprint" ""
			(at 88.9 189.23 0)
			(effects
				(font
					(size 1.27 1.27)
					(thickness 0.15)
				)
				(justify left bottom)
				(hide yes)
			)
		)
		(property "Datasheet" ""
			(at 88.9 194.31 0)
			(effects
				(font
					(size 1.27 1.27)
					(thickness 0.15)
				)
				(justify left bottom)
				(hide yes)
			)
		)
		(property "Description" ""
			(at 97.79 181.61 0)
			(effects
				(font
					(size 1.27 1.27)
				)
				(hide yes)
			)
		)
		(property "Author" "Antmicro"
			(at 88.9 189.23 0)
			(effects
				(font
					(size 1.27 1.27)
					(thickness 0.15)
				)
				(justify left bottom)
				(hide yes)
			)
		)
		(property "License" "Apache-2.0"
			(at 88.9 191.77 0)
			(effects
				(font
					(size 1.27 1.27)
					(thickness 0.15)
				)
				(justify left bottom)
				(hide yes)
			)
		)
		(pin "1"
		)
		(instances
			(project "OCuLink to 10GbE adapter"
				(path ""
					(reference "#PWR0109")
					(unit 1)
				)
			)
		)
	)
	(symbol
		(lib_id "antmicropower:GND")
		(at 274.32 132.08 0)
		(unit 1)
		(exclude_from_sim no)
		(in_bom yes)
		(on_board yes)
		(dnp no)
		(property "Reference" "#PWR0274"
			(at 283.21 134.62 0)
			(effects
				(font
					(size 1.27 1.27)
					(thickness 0.15)
				)
				(justify left bottom)
				(hide yes)
			)
		)
		(property "Value" "GND"
			(at 274.32 135.89 0)
			(effects
				(font
					(size 1.27 1.27)
					(thickness 0.15)
				)
			)
		)
		(property "Footprint" ""
			(at 283.21 139.7 0)
			(effects
				(font
					(size 1.27 1.27)
					(thickness 0.15)
				)
				(justify left bottom)
				(hide yes)
			)
		)
		(property "Datasheet" ""
			(at 283.21 144.78 0)
			(effects
				(font
					(size 1.27 1.27)
					(thickness 0.15)
				)
				(justify left bottom)
				(hide yes)
			)
		)
		(property "Description" ""
			(at 274.32 132.08 0)
			(effects
				(font
					(size 1.27 1.27)
				)
				(hide yes)
			)
		)
		(property "Author" "Antmicro"
			(at 283.21 139.7 0)
			(effects
				(font
					(size 1.27 1.27)
					(thickness 0.15)
				)
				(justify left bottom)
				(hide yes)
			)
		)
		(property "License" "Apache-2.0"
			(at 283.21 142.24 0)
			(effects
				(font
					(size 1.27 1.27)
					(thickness 0.15)
				)
				(justify left bottom)
				(hide yes)
			)
		)
		(pin "1"
		)
		(instances
			(project "OCuLink to 10GbE adapter"
				(path ""
					(reference "#PWR0274")
					(unit 1)
				)
			)
		)
	)
	(symbol
		(lib_id "antmicroTestPoints:TP_0.75mm_SMD")
		(at 92.71 68.58 180)
		(unit 1)
		(exclude_from_sim no)
		(in_bom no)
		(on_board yes)
		(dnp no)
		(property "Reference" "TP8"
			(at 88.392 68.58 0)
			(effects
				(font
					(size 1.27 1.27)
					(thickness 0.15)
				)
				(justify left)
			)
		)
		(property "Value" "TP_0.75mm_SMD"
			(at 82.55 64.77 0)
			(effects
				(font
					(size 1.27 1.27)
					(thickness 0.15)
				)
				(justify left bottom)
				(hide yes)
			)
		)
		(property "Footprint" "antmicro-footprints:TP_SMD_0.75mm"
			(at 82.55 62.23 0)
			(effects
				(font
					(size 1.27 1.27)
					(thickness 0.15)
				)
				(justify left bottom)
				(hide yes)
			)
		)
		(property "Datasheet" ""
			(at 74.93 55.88 0)
			(effects
				(font
					(size 1.27 1.27)
					(thickness 0.15)
				)
				(justify left bottom)
				(hide yes)
			)
		)
		(property "Description" "SMT test point"
			(at 92.71 68.58 0)
			(effects
				(font
					(size 1.27 1.27)
				)
				(hide yes)
			)
		)
		(property "MPN" ""
			(at 81.915 57.15 0)
			(effects
				(font
					(size 1.27 1.27)
					(thickness 0.15)
				)
				(justify left bottom)
				(hide yes)
			)
		)
		(property "Manufacturer" ""
			(at 81.915 62.23 0)
			(effects
				(font
					(size 1.27 1.27)
					(thickness 0.15)
				)
				(justify left bottom)
				(hide yes)
			)
		)
		(property "Author" "Antmicro"
			(at 82.55 59.69 0)
			(effects
				(font
					(size 1.27 1.27)
					(thickness 0.15)
				)
				(justify left bottom)
				(hide yes)
			)
		)
		(property "License" "Apache-2.0"
			(at 82.55 57.15 0)
			(effects
				(font
					(size 1.27 1.27)
					(thickness 0.15)
				)
				(justify left bottom)
				(hide yes)
			)
		)
		(pin "1"
		)
		(instances
			(project "OCuLink to 10GbE adapter"
				(path ""
					(reference "TP8")
					(unit 1)
				)
			)
		)
	)
	(symbol
		(lib_id "antmicroCapacitors0402:C_100n_0402")
		(at 62.23 179.07 270)
		(mirror x)
		(unit 1)
		(exclude_from_sim no)
		(in_bom yes)
		(on_board yes)
		(dnp no)
		(property "Reference" "C77"
			(at 60.198 175.26 90)
			(effects
				(font
					(size 1.27 1.27)
					(thickness 0.15)
				)
				(justify right)
			)
		)
		(property "Value" "C_100n_0402"
			(at 39.37 163.83 0)
			(effects
				(font
					(size 1.27 1.27)
					(thickness 0.15)
				)
				(justify left bottom)
				(hide yes)
			)
		)
		(property "Footprint" "antmicro-footprints:C_0402_1005Metric"
			(at 36.83 163.83 0)
			(effects
				(font
					(size 1.27 1.27)
					(thickness 0.15)
				)
				(justify left bottom)
				(hide yes)
			)
		)
		(property "Datasheet" "https://www.murata.com/products/productdetail?partno=GRM155R61H104KE14%23"
			(at 34.29 163.83 0)
			(effects
				(font
					(size 1.27 1.27)
					(thickness 0.15)
				)
				(justify left bottom)
				(hide yes)
			)
		)
		(property "Description" "SMD Multilayer Ceramic Capacitor, 0.1 µF, 50 V, 0402 [1005 Metric], ± 10%, X5R, GRM Series"
			(at 62.23 179.07 0)
			(effects
				(font
					(size 1.27 1.27)
				)
				(hide yes)
			)
		)
		(property "MPN" "GRM155R61H104KE14D"
			(at 31.75 163.83 0)
			(effects
				(font
					(size 1.27 1.27)
					(thickness 0.15)
				)
				(justify left bottom)
				(hide yes)
			)
		)
		(property "Val" "100n"
			(at 60.198 177.8 90)
			(effects
				(font
					(size 1.27 1.27)
					(thickness 0.15)
				)
				(justify right)
			)
		)
		(property "Voltage" "50V"
			(at 52.07 163.83 0)
			(effects
				(font
					(size 1.27 1.27)
					(thickness 0.15)
				)
				(justify left bottom)
				(hide yes)
			)
		)
		(property "Dielectric" "X5R"
			(at 49.53 163.83 0)
			(effects
				(font
					(size 1.27 1.27)
					(thickness 0.15)
				)
				(justify left bottom)
				(hide yes)
			)
		)
		(property "Manufacturer" "Murata"
			(at 46.99 163.83 0)
			(effects
				(font
					(size 1.27 1.27)
					(thickness 0.15)
				)
				(justify left bottom)
				(hide yes)
			)
		)
		(property "License" "Apache-2.0"
			(at 44.45 163.83 0)
			(effects
				(font
					(size 1.27 1.27)
					(thickness 0.15)
				)
				(justify left bottom)
				(hide yes)
			)
		)
		(property "Author" "Antmicro"
			(at 41.91 163.83 0)
			(effects
				(font
					(size 1.27 1.27)
					(thickness 0.15)
				)
				(justify left bottom)
				(hide yes)
			)
		)
		(pin "2"
		)
		(pin "1"
		)
		(instances
			(project "OCuLink to 10GbE adapter"
				(path ""
					(reference "C77")
					(unit 1)
				)
			)
		)
	)
	(symbol
		(lib_id "antmicroTestPoints:TP_0.75mm_SMD")
		(at 170.18 231.14 180)
		(unit 1)
		(exclude_from_sim no)
		(in_bom no)
		(on_board yes)
		(dnp no)
		(property "Reference" "TP12"
			(at 165.862 231.14 0)
			(effects
				(font
					(size 1.27 1.27)
					(thickness 0.15)
				)
				(justify left)
			)
		)
		(property "Value" "TP_0.75mm_SMD"
			(at 160.02 227.33 0)
			(effects
				(font
					(size 1.27 1.27)
					(thickness 0.15)
				)
				(justify left bottom)
				(hide yes)
			)
		)
		(property "Footprint" "antmicro-footprints:TP_SMD_0.75mm"
			(at 160.02 224.79 0)
			(effects
				(font
					(size 1.27 1.27)
					(thickness 0.15)
				)
				(justify left bottom)
				(hide yes)
			)
		)
		(property "Datasheet" ""
			(at 152.4 218.44 0)
			(effects
				(font
					(size 1.27 1.27)
					(thickness 0.15)
				)
				(justify left bottom)
				(hide yes)
			)
		)
		(property "Description" "SMT test point"
			(at 170.18 231.14 0)
			(effects
				(font
					(size 1.27 1.27)
				)
				(hide yes)
			)
		)
		(property "MPN" ""
			(at 159.385 219.71 0)
			(effects
				(font
					(size 1.27 1.27)
					(thickness 0.15)
				)
				(justify left bottom)
				(hide yes)
			)
		)
		(property "Manufacturer" ""
			(at 159.385 224.79 0)
			(effects
				(font
					(size 1.27 1.27)
					(thickness 0.15)
				)
				(justify left bottom)
				(hide yes)
			)
		)
		(property "Author" "Antmicro"
			(at 160.02 222.25 0)
			(effects
				(font
					(size 1.27 1.27)
					(thickness 0.15)
				)
				(justify left bottom)
				(hide yes)
			)
		)
		(property "License" "Apache-2.0"
			(at 160.02 219.71 0)
			(effects
				(font
					(size 1.27 1.27)
					(thickness 0.15)
				)
				(justify left bottom)
				(hide yes)
			)
		)
		(pin "1"
		)
		(instances
			(project "OCuLink to 10GbE adapter"
				(path ""
					(reference "TP12")
					(unit 1)
				)
			)
		)
	)
	(symbol
		(lib_id "antmicroResistors0402:R_8k2_0402")
		(at 274.32 129.54 90)
		(unit 1)
		(exclude_from_sim no)
		(in_bom yes)
		(on_board yes)
		(dnp no)
		(property "Reference" "R110"
			(at 275.844 125.73 90)
			(effects
				(font
					(size 1.27 1.27)
					(thickness 0.15)
				)
				(justify right)
			)
		)
		(property "Value" "R_8k2_0402"
			(at 287.02 109.22 0)
			(effects
				(font
					(size 1.27 1.27)
					(thickness 0.15)
				)
				(justify left bottom)
				(hide yes)
			)
		)
		(property "Footprint" "antmicro-footprints:R_0402_1005Metric"
			(at 289.56 109.22 0)
			(effects
				(font
					(size 1.27 1.27)
					(thickness 0.15)
				)
				(justify left bottom)
				(hide yes)
			)
		)
		(property "Datasheet" "https://www.bourns.com/docs/product-datasheets/cr.pdf"
			(at 292.1 109.22 0)
			(effects
				(font
					(size 1.27 1.27)
					(thickness 0.15)
				)
				(justify left bottom)
				(hide yes)
			)
		)
		(property "Description" "SMD Chip Resistor"
			(at 274.32 129.54 0)
			(effects
				(font
					(size 1.27 1.27)
				)
				(hide yes)
			)
		)
		(property "MPN" "CR0402-FX-8201GLF"
			(at 294.64 109.22 0)
			(effects
				(font
					(size 1.27 1.27)
					(thickness 0.15)
				)
				(justify left bottom)
				(hide yes)
			)
		)
		(property "Manufacturer" "Bourns"
			(at 297.18 109.22 0)
			(effects
				(font
					(size 1.27 1.27)
					(thickness 0.15)
				)
				(justify left bottom)
				(hide yes)
			)
		)
		(property "License" "Apache-2.0"
			(at 299.72 109.22 0)
			(effects
				(font
					(size 1.27 1.27)
					(thickness 0.15)
				)
				(justify left bottom)
				(hide yes)
			)
		)
		(property "Author" "Antmicro"
			(at 302.26 109.22 0)
			(effects
				(font
					(size 1.27 1.27)
					(thickness 0.15)
				)
				(justify left bottom)
				(hide yes)
			)
		)
		(property "Val" "8k2"
			(at 275.844 128.27 90)
			(effects
				(font
					(size 1.27 1.27)
					(thickness 0.15)
				)
				(justify right)
			)
		)
		(property "Tolerance" "1%"
			(at 284.48 109.22 0)
			(effects
				(font
					(size 1.27 1.27)
				)
				(justify left bottom)
				(hide yes)
			)
		)
		(pin "1"
		)
		(pin "2"
		)
		(instances
			(project ""
				(path ""
					(reference "R110")
					(unit 1)
				)
			)
		)
	)
	(symbol
		(lib_id "antmicropower:GND")
		(at 135.89 132.08 0)
		(unit 1)
		(exclude_from_sim no)
		(in_bom yes)
		(on_board yes)
		(dnp no)
		(property "Reference" "#PWR0271"
			(at 144.78 134.62 0)
			(effects
				(font
					(size 1.27 1.27)
					(thickness 0.15)
				)
				(justify left bottom)
				(hide yes)
			)
		)
		(property "Value" "GND"
			(at 135.89 135.89 0)
			(effects
				(font
					(size 1.27 1.27)
					(thickness 0.15)
				)
			)
		)
		(property "Footprint" ""
			(at 144.78 139.7 0)
			(effects
				(font
					(size 1.27 1.27)
					(thickness 0.15)
				)
				(justify left bottom)
				(hide yes)
			)
		)
		(property "Datasheet" ""
			(at 144.78 144.78 0)
			(effects
				(font
					(size 1.27 1.27)
					(thickness 0.15)
				)
				(justify left bottom)
				(hide yes)
			)
		)
		(property "Description" ""
			(at 135.89 132.08 0)
			(effects
				(font
					(size 1.27 1.27)
				)
				(hide yes)
			)
		)
		(property "Author" "Antmicro"
			(at 144.78 139.7 0)
			(effects
				(font
					(size 1.27 1.27)
					(thickness 0.15)
				)
				(justify left bottom)
				(hide yes)
			)
		)
		(property "License" "Apache-2.0"
			(at 144.78 142.24 0)
			(effects
				(font
					(size 1.27 1.27)
					(thickness 0.15)
				)
				(justify left bottom)
				(hide yes)
			)
		)
		(pin "1"
		)
		(instances
			(project "OCuLink to 10GbE adapter"
				(path ""
					(reference "#PWR0271")
					(unit 1)
				)
			)
		)
	)
)
